FILE_TYPE = MACRO_DRAWING;
SET COLOR_WIRE YELLOW;
SET COLOR_PROP ORANGE;
SET COLOR_DOT WHITE;
SET COLOR_ARC YELLOW;
SET COLOR_BODY GREEN;
SET COLOR_NOTE PURPLE;
SET PROP_DISPLAY VALUE;
SET PAGE_NUMBER P320;
FORCEADD OFFPAGE..1
(-3250 -925);
FORCEPROP 2 LAST $XR0 173 
J 0
(-3502 -925);
DISPLAY 0.638298 (-3502 -925);
PAINT MONO (-3502 -925);
FORCEPROP 2 LAST PATH I1
J 0
(-3500 -875);
DISPLAY 1.021277 (-3500 -875);
DISPLAY INVISIBLE (-3500 -875);
FORCEPROP 1 LAST OFFPAGE TRUE
J 0
(-2925 -1050);
DISPLAY 0.872340 (-2925 -1050);
PAINT AQUA (-2925 -1050);
DISPLAY INVISIBLE (-2925 -1050);
FORCEPROP 1 LAST COMMENT_BODY TRUE
J 0
(-3125 -1025);
DISPLAY 0.872340 (-3125 -1025);
PAINT GREEN (-3125 -1025);
DISPLAY INVISIBLE (-3125 -1025);
FORCEPROP 2 LAST CDS_LIB standard
J 0
(-3250 -925);
DISPLAY INVISIBLE (-3250 -925);
FORCEADD OFFPAGE..1
(-3250 -175);
FORCEPROP 2 LAST $XR0 175 
J 0
(-3502 -175);
DISPLAY 0.638298 (-3502 -175);
PAINT MONO (-3502 -175);
FORCEPROP 2 LAST PATH I10
J 0
(-3500 -125);
DISPLAY 1.021277 (-3500 -125);
DISPLAY INVISIBLE (-3500 -125);
FORCEPROP 1 LAST OFFPAGE TRUE
J 0
(-2925 -300);
DISPLAY 0.872340 (-2925 -300);
PAINT AQUA (-2925 -300);
DISPLAY INVISIBLE (-2925 -300);
FORCEPROP 1 LAST COMMENT_BODY TRUE
J 0
(-3125 -275);
DISPLAY 0.872340 (-3125 -275);
PAINT GREEN (-3125 -275);
DISPLAY INVISIBLE (-3125 -275);
FORCEPROP 2 LAST CDS_LIB standard
J 0
(-3250 -175);
DISPLAY INVISIBLE (-3250 -175);
FORCEADD OFFPAGE..1
(-3250 -225);
FORCEPROP 2 LAST $XR0 175 
J 0
(-3502 -225);
DISPLAY 0.638298 (-3502 -225);
PAINT MONO (-3502 -225);
FORCEPROP 2 LAST PATH I11
J 0
(-3500 -175);
DISPLAY 1.021277 (-3500 -175);
DISPLAY INVISIBLE (-3500 -175);
FORCEPROP 1 LAST OFFPAGE TRUE
J 0
(-2925 -350);
DISPLAY 0.872340 (-2925 -350);
PAINT AQUA (-2925 -350);
DISPLAY INVISIBLE (-2925 -350);
FORCEPROP 1 LAST COMMENT_BODY TRUE
J 0
(-3125 -325);
DISPLAY 0.872340 (-3125 -325);
PAINT GREEN (-3125 -325);
DISPLAY INVISIBLE (-3125 -325);
FORCEPROP 2 LAST CDS_LIB standard
J 0
(-3250 -225);
DISPLAY INVISIBLE (-3250 -225);
FORCEADD OFFPAGE..1
(-3250 -75);
FORCEPROP 2 LAST $XR0 173 
J 0
(-3502 -75);
DISPLAY 0.638298 (-3502 -75);
PAINT MONO (-3502 -75);
FORCEPROP 2 LAST PATH I13
J 0
(-3500 -25);
DISPLAY 1.021277 (-3500 -25);
DISPLAY INVISIBLE (-3500 -25);
FORCEPROP 2 LAST CDS_LIB standard
J 0
(-3250 -75);
DISPLAY INVISIBLE (-3250 -75);
FORCEPROP 1 LAST COMMENT_BODY TRUE
J 0
(-3125 -175);
DISPLAY 0.872340 (-3125 -175);
PAINT GREEN (-3125 -175);
DISPLAY INVISIBLE (-3125 -175);
FORCEPROP 1 LAST OFFPAGE TRUE
J 0
(-2925 -200);
DISPLAY 0.872340 (-2925 -200);
PAINT AQUA (-2925 -200);
DISPLAY INVISIBLE (-2925 -200);
FORCEADD OFFPAGE..1
(-3250 -25);
FORCEPROP 2 LAST $XR0 173 
J 0
(-3502 -25);
DISPLAY 0.638298 (-3502 -25);
PAINT MONO (-3502 -25);
FORCEPROP 2 LAST PATH I14
J 0
(-3500 25);
DISPLAY 1.021277 (-3500 25);
DISPLAY INVISIBLE (-3500 25);
FORCEPROP 2 LAST CDS_LIB standard
J 0
(-3250 -25);
DISPLAY INVISIBLE (-3250 -25);
FORCEPROP 1 LAST COMMENT_BODY TRUE
J 0
(-3125 -125);
DISPLAY 0.872340 (-3125 -125);
PAINT GREEN (-3125 -125);
DISPLAY INVISIBLE (-3125 -125);
FORCEPROP 1 LAST OFFPAGE TRUE
J 0
(-2925 -150);
DISPLAY 0.872340 (-2925 -150);
PAINT AQUA (-2925 -150);
DISPLAY INVISIBLE (-2925 -150);
FORCEADD OFFPAGE..5
(-3250 75);
FORCEPROP 2 LAST $XR0 31 
J 0
(-3504 75);
DISPLAY 0.638298 (-3504 75);
PAINT MONO (-3504 75);
FORCEPROP 2 LAST PATH I15
J 0
(-3500 125);
DISPLAY 1.021277 (-3500 125);
DISPLAY INVISIBLE (-3500 125);
FORCEPROP 1 LAST OFFPAGE TRUE
J 0
(-2925 -50);
DISPLAY 0.872340 (-2925 -50);
PAINT AQUA (-2925 -50);
DISPLAY INVISIBLE (-2925 -50);
FORCEPROP 1 LAST COMMENT_BODY TRUE
J 0
(-3150 0);
DISPLAY 1.170213 (-3150 0);
PAINT GREEN (-3150 0);
DISPLAY INVISIBLE (-3150 0);
FORCEPROP 2 LAST CDS_LIB standard
J 0
(-3250 75);
DISPLAY INVISIBLE (-3250 75);
FORCEADD OFFPAGE..2
R 2
(-3250 125);
FORCEPROP 2 LAST $XR0 31 
J 0
(-3504 125);
DISPLAY 0.638298 (-3504 125);
PAINT MONO (-3504 125);
FORCEPROP 2 LAST PATH I16
J 0
(-3500 175);
DISPLAY 1.021277 (-3500 175);
DISPLAY INVISIBLE (-3500 175);
FORCEPROP 1 LAST OFFPAGE TRUE
J 2
(-3575 0);
DISPLAY 0.872340 (-3575 0);
PAINT AQUA (-3575 0);
DISPLAY INVISIBLE (-3575 0);
FORCEPROP 1 LAST COMMENT_BODY TRUE
J 2
(-3205 30);
DISPLAY 0.872340 (-3205 30);
PAINT GREEN (-3205 30);
DISPLAY INVISIBLE (-3205 30);
FORCEPROP 2 LAST CDS_LIB standard
J 0
(-3250 125);
DISPLAY INVISIBLE (-3250 125);
FORCEADD OFFPAGE..2
R 2
(-3250 275);
FORCEPROP 2 LAST $XR0 29 
J 0
(-3504 275);
DISPLAY 0.638298 (-3504 275);
PAINT MONO (-3504 275);
FORCEPROP 2 LAST PATH I17
J 0
(-3500 325);
DISPLAY 1.021277 (-3500 325);
DISPLAY INVISIBLE (-3500 325);
FORCEPROP 1 LAST OFFPAGE TRUE
J 2
(-3575 150);
DISPLAY 0.872340 (-3575 150);
PAINT AQUA (-3575 150);
DISPLAY INVISIBLE (-3575 150);
FORCEPROP 1 LAST COMMENT_BODY TRUE
J 2
(-3205 180);
DISPLAY 0.872340 (-3205 180);
PAINT GREEN (-3205 180);
DISPLAY INVISIBLE (-3205 180);
FORCEPROP 2 LAST CDS_LIB standard
J 0
(-3250 275);
DISPLAY INVISIBLE (-3250 275);
FORCEADD OFFPAGE..5
(-3250 225);
FORCEPROP 2 LAST $XR0 29 
J 0
(-3504 225);
DISPLAY 0.638298 (-3504 225);
PAINT MONO (-3504 225);
FORCEPROP 2 LAST PATH I18
J 0
(-3500 275);
DISPLAY 1.021277 (-3500 275);
DISPLAY INVISIBLE (-3500 275);
FORCEPROP 1 LAST OFFPAGE TRUE
J 0
(-2925 100);
DISPLAY 0.872340 (-2925 100);
PAINT AQUA (-2925 100);
DISPLAY INVISIBLE (-2925 100);
FORCEPROP 1 LAST COMMENT_BODY TRUE
J 0
(-3150 150);
DISPLAY 1.170213 (-3150 150);
PAINT GREEN (-3150 150);
DISPLAY INVISIBLE (-3150 150);
FORCEPROP 2 LAST CDS_LIB standard
J 0
(-3250 225);
DISPLAY INVISIBLE (-3250 225);
FORCEADD UNIVERSAL_GND..1
(-2150 -1475);
FORCEPROP 3 LASTPIN (-2150 -1425) SIG_NAME GND\g
J 0
(-2140 -1415);
DISPLAY 0.659574 (-2140 -1415);
PAINT MONO (-2140 -1415);
DISPLAY INVISIBLE (-2140 -1415);
FORCEPROP 1 LAST PATH I19
J 0
(-2075 -1475);
DISPLAY 0.872340 (-2075 -1475);
PAINT AQUA (-2075 -1475);
DISPLAY INVISIBLE (-2075 -1475);
FORCEPROP 2 LAST CDS_LIB logical_power
J 0
(-2150 -1475);
DISPLAY INVISIBLE (-2150 -1475);
FORCEPROP 1 LAST HDL_POWER GND
J 1
(-2125 -1550);
DISPLAY 0.872340 (-2125 -1550);
PAINT GREEN (-2125 -1550);
DISPLAY INVISIBLE (-2125 -1550);
FORCEADD OFFPAGE..1
(-3250 -1025);
FORCEPROP 2 LAST $XR0 175 
J 0
(-3502 -1025);
DISPLAY 0.638298 (-3502 -1025);
PAINT MONO (-3502 -1025);
FORCEPROP 2 LAST PATH I2
J 0
(-3500 -975);
DISPLAY 1.021277 (-3500 -975);
DISPLAY INVISIBLE (-3500 -975);
FORCEPROP 1 LAST OFFPAGE TRUE
J 0
(-2925 -1150);
DISPLAY 0.872340 (-2925 -1150);
PAINT AQUA (-2925 -1150);
DISPLAY INVISIBLE (-2925 -1150);
FORCEPROP 1 LAST COMMENT_BODY TRUE
J 0
(-3125 -1125);
DISPLAY 0.872340 (-3125 -1125);
PAINT GREEN (-3125 -1125);
DISPLAY INVISIBLE (-3125 -1125);
FORCEPROP 2 LAST CDS_LIB standard
J 0
(-3250 -1025);
DISPLAY INVISIBLE (-3250 -1025);
FORCEADD OFFPAGE..1
(-3250 575);
FORCEPROP 2 LAST $XR0 175 
J 0
(-3502 575);
DISPLAY 0.638298 (-3502 575);
PAINT MONO (-3502 575);
FORCEPROP 2 LAST PATH I20
J 0
(-3500 625);
DISPLAY 1.021277 (-3500 625);
DISPLAY INVISIBLE (-3500 625);
FORCEPROP 1 LAST OFFPAGE TRUE
J 0
(-2925 450);
DISPLAY 0.872340 (-2925 450);
PAINT AQUA (-2925 450);
DISPLAY INVISIBLE (-2925 450);
FORCEPROP 1 LAST COMMENT_BODY TRUE
J 0
(-3125 475);
DISPLAY 0.872340 (-3125 475);
PAINT GREEN (-3125 475);
DISPLAY INVISIBLE (-3125 475);
FORCEPROP 2 LAST CDS_LIB standard
J 0
(-3250 575);
DISPLAY INVISIBLE (-3250 575);
FORCEADD OFFPAGE..1
(-3250 525);
FORCEPROP 2 LAST $XR0 175 
J 0
(-3502 525);
DISPLAY 0.638298 (-3502 525);
PAINT MONO (-3502 525);
FORCEPROP 2 LAST PATH I21
J 0
(-3500 575);
DISPLAY 1.021277 (-3500 575);
DISPLAY INVISIBLE (-3500 575);
FORCEPROP 2 LAST CDS_LIB standard
J 0
(-3250 525);
DISPLAY INVISIBLE (-3250 525);
FORCEPROP 1 LAST COMMENT_BODY TRUE
J 0
(-3125 425);
DISPLAY 0.872340 (-3125 425);
PAINT GREEN (-3125 425);
DISPLAY INVISIBLE (-3125 425);
FORCEPROP 1 LAST OFFPAGE TRUE
J 0
(-2925 400);
DISPLAY 0.872340 (-2925 400);
PAINT AQUA (-2925 400);
DISPLAY INVISIBLE (-2925 400);
FORCEADD OFFPAGE..1
(-3250 675);
FORCEPROP 2 LAST $XR0 173 
J 0
(-3502 675);
DISPLAY 0.638298 (-3502 675);
PAINT MONO (-3502 675);
FORCEPROP 2 LAST PATH I22
J 0
(-3500 725);
DISPLAY 1.021277 (-3500 725);
DISPLAY INVISIBLE (-3500 725);
FORCEPROP 2 LAST CDS_LIB standard
J 0
(-3250 675);
DISPLAY INVISIBLE (-3250 675);
FORCEPROP 1 LAST COMMENT_BODY TRUE
J 0
(-3125 575);
DISPLAY 0.872340 (-3125 575);
PAINT GREEN (-3125 575);
DISPLAY INVISIBLE (-3125 575);
FORCEPROP 1 LAST OFFPAGE TRUE
J 0
(-2925 550);
DISPLAY 0.872340 (-2925 550);
PAINT AQUA (-2925 550);
DISPLAY INVISIBLE (-2925 550);
FORCEADD OFFPAGE..1
(-3250 725);
FORCEPROP 2 LAST $XR0 173 
J 0
(-3502 725);
DISPLAY 0.638298 (-3502 725);
PAINT MONO (-3502 725);
FORCEPROP 2 LAST PATH I23
J 0
(-3500 775);
DISPLAY 1.021277 (-3500 775);
DISPLAY INVISIBLE (-3500 775);
FORCEPROP 1 LAST OFFPAGE TRUE
J 0
(-2925 600);
DISPLAY 0.872340 (-2925 600);
PAINT AQUA (-2925 600);
DISPLAY INVISIBLE (-2925 600);
FORCEPROP 1 LAST COMMENT_BODY TRUE
J 0
(-3125 625);
DISPLAY 0.872340 (-3125 625);
PAINT GREEN (-3125 625);
DISPLAY INVISIBLE (-3125 625);
FORCEPROP 2 LAST CDS_LIB standard
J 0
(-3250 725);
DISPLAY INVISIBLE (-3250 725);
FORCEADD OFFPAGE..5
(-3250 825);
FORCEPROP 2 LAST $XR0 31 
J 0
(-3504 825);
DISPLAY 0.638298 (-3504 825);
PAINT MONO (-3504 825);
FORCEPROP 2 LAST PATH I24
J 0
(-3500 875);
DISPLAY 1.021277 (-3500 875);
DISPLAY INVISIBLE (-3500 875);
FORCEPROP 2 LAST CDS_LIB standard
J 0
(-3250 825);
DISPLAY INVISIBLE (-3250 825);
FORCEPROP 1 LAST COMMENT_BODY TRUE
J 0
(-3150 750);
DISPLAY 1.170213 (-3150 750);
PAINT GREEN (-3150 750);
DISPLAY INVISIBLE (-3150 750);
FORCEPROP 1 LAST OFFPAGE TRUE
J 0
(-2925 700);
DISPLAY 0.872340 (-2925 700);
PAINT AQUA (-2925 700);
DISPLAY INVISIBLE (-2925 700);
FORCEADD OFFPAGE..2
R 2
(-3250 875);
FORCEPROP 2 LAST $XR0 31 
J 0
(-3504 875);
DISPLAY 0.638298 (-3504 875);
PAINT MONO (-3504 875);
FORCEPROP 2 LAST PATH I25
J 0
(-3500 925);
DISPLAY 1.021277 (-3500 925);
DISPLAY INVISIBLE (-3500 925);
FORCEPROP 2 LAST CDS_LIB standard
J 0
(-3250 875);
DISPLAY INVISIBLE (-3250 875);
FORCEPROP 1 LAST COMMENT_BODY TRUE
J 2
(-3205 780);
DISPLAY 0.872340 (-3205 780);
PAINT GREEN (-3205 780);
DISPLAY INVISIBLE (-3205 780);
FORCEPROP 1 LAST OFFPAGE TRUE
J 2
(-3575 750);
DISPLAY 0.872340 (-3575 750);
PAINT AQUA (-3575 750);
DISPLAY INVISIBLE (-3575 750);
FORCEADD OFFPAGE..5
(-3250 975);
FORCEPROP 2 LAST $XR0 29 
J 0
(-3504 975);
DISPLAY 0.638298 (-3504 975);
PAINT MONO (-3504 975);
FORCEPROP 2 LAST PATH I26
J 0
(-3500 1025);
DISPLAY 1.021277 (-3500 1025);
DISPLAY INVISIBLE (-3500 1025);
FORCEPROP 2 LAST CDS_LIB standard
J 0
(-3250 975);
DISPLAY INVISIBLE (-3250 975);
FORCEPROP 1 LAST COMMENT_BODY TRUE
J 0
(-3150 900);
DISPLAY 1.170213 (-3150 900);
PAINT GREEN (-3150 900);
DISPLAY INVISIBLE (-3150 900);
FORCEPROP 1 LAST OFFPAGE TRUE
J 0
(-2925 850);
DISPLAY 0.872340 (-2925 850);
PAINT AQUA (-2925 850);
DISPLAY INVISIBLE (-2925 850);
FORCEADD OFFPAGE..2
R 2
(-3250 1025);
FORCEPROP 2 LAST $XR0 29 
J 0
(-3504 1025);
DISPLAY 0.638298 (-3504 1025);
PAINT MONO (-3504 1025);
FORCEPROP 2 LAST PATH I27
J 0
(-3500 1075);
DISPLAY 1.021277 (-3500 1075);
DISPLAY INVISIBLE (-3500 1075);
FORCEPROP 1 LAST OFFPAGE TRUE
J 2
(-3575 900);
DISPLAY 0.872340 (-3575 900);
PAINT AQUA (-3575 900);
DISPLAY INVISIBLE (-3575 900);
FORCEPROP 1 LAST COMMENT_BODY TRUE
J 2
(-3205 930);
DISPLAY 0.872340 (-3205 930);
PAINT GREEN (-3205 930);
DISPLAY INVISIBLE (-3205 930);
FORCEPROP 2 LAST CDS_LIB standard
J 0
(-3250 1025);
DISPLAY INVISIBLE (-3250 1025);
FORCEADD OFFPAGE..1
(-3250 -1075);
FORCEPROP 2 LAST $XR0 175 
J 0
(-3502 -1075);
DISPLAY 0.638298 (-3502 -1075);
PAINT MONO (-3502 -1075);
FORCEPROP 2 LAST PATH I3
J 0
(-3500 -1025);
DISPLAY 1.021277 (-3500 -1025);
DISPLAY INVISIBLE (-3500 -1025);
FORCEPROP 1 LAST OFFPAGE TRUE
J 0
(-2925 -1200);
DISPLAY 0.872340 (-2925 -1200);
PAINT AQUA (-2925 -1200);
DISPLAY INVISIBLE (-2925 -1200);
FORCEPROP 1 LAST COMMENT_BODY TRUE
J 0
(-3125 -1175);
DISPLAY 0.872340 (-3125 -1175);
PAINT GREEN (-3125 -1175);
DISPLAY INVISIBLE (-3125 -1175);
FORCEPROP 2 LAST CDS_LIB standard
J 0
(-3250 -1075);
DISPLAY INVISIBLE (-3250 -1075);
FORCEADD OFFPAGE..1
(-3250 1375);
FORCEPROP 2 LAST $XR0 175 
J 0
(-3502 1375);
DISPLAY 0.638298 (-3502 1375);
PAINT MONO (-3502 1375);
FORCEPROP 2 LAST PATH I30
J 0
(-3500 1425);
DISPLAY 1.021277 (-3500 1425);
DISPLAY INVISIBLE (-3500 1425);
FORCEPROP 1 LAST OFFPAGE TRUE
J 0
(-2925 1250);
DISPLAY 0.872340 (-2925 1250);
PAINT AQUA (-2925 1250);
DISPLAY INVISIBLE (-2925 1250);
FORCEPROP 1 LAST COMMENT_BODY TRUE
J 0
(-3125 1275);
DISPLAY 0.872340 (-3125 1275);
PAINT GREEN (-3125 1275);
DISPLAY INVISIBLE (-3125 1275);
FORCEPROP 2 LAST CDS_LIB standard
J 0
(-3250 1375);
DISPLAY INVISIBLE (-3250 1375);
FORCEADD OFFPAGE..1
(-3250 1425);
FORCEPROP 2 LAST $XR0 175 
J 0
(-3502 1425);
DISPLAY 0.638298 (-3502 1425);
PAINT MONO (-3502 1425);
FORCEPROP 2 LAST PATH I31
J 0
(-3500 1475);
DISPLAY 1.021277 (-3500 1475);
DISPLAY INVISIBLE (-3500 1475);
FORCEPROP 1 LAST OFFPAGE TRUE
J 0
(-2925 1300);
DISPLAY 0.872340 (-2925 1300);
PAINT AQUA (-2925 1300);
DISPLAY INVISIBLE (-2925 1300);
FORCEPROP 1 LAST COMMENT_BODY TRUE
J 0
(-3125 1325);
DISPLAY 0.872340 (-3125 1325);
PAINT GREEN (-3125 1325);
DISPLAY INVISIBLE (-3125 1325);
FORCEPROP 2 LAST CDS_LIB standard
J 0
(-3250 1425);
DISPLAY INVISIBLE (-3250 1425);
FORCEADD OFFPAGE..5
(-3250 1675);
FORCEPROP 2 LAST $XR0 31 
J 0
(-3504 1675);
DISPLAY 0.638298 (-3504 1675);
PAINT MONO (-3504 1675);
FORCEPROP 2 LAST CDS_LIB standard
J 0
(-3250 1675);
DISPLAY INVISIBLE (-3250 1675);
FORCEPROP 2 LAST PATH I32
J 0
(-3500 1725);
DISPLAY 1.021277 (-3500 1725);
DISPLAY INVISIBLE (-3500 1725);
FORCEPROP 1 LAST COMMENT_BODY TRUE
J 0
(-3150 1600);
DISPLAY 1.170213 (-3150 1600);
PAINT GREEN (-3150 1600);
DISPLAY INVISIBLE (-3150 1600);
FORCEPROP 1 LAST OFFPAGE TRUE
J 0
(-2925 1550);
DISPLAY 0.872340 (-2925 1550);
PAINT AQUA (-2925 1550);
DISPLAY INVISIBLE (-2925 1550);
FORCEADD OFFPAGE..1
(-3250 1525);
FORCEPROP 2 LAST $XR0 173 
J 0
(-3502 1525);
DISPLAY 0.638298 (-3502 1525);
PAINT MONO (-3502 1525);
FORCEPROP 2 LAST PATH I33
J 0
(-3500 1575);
DISPLAY 1.021277 (-3500 1575);
DISPLAY INVISIBLE (-3500 1575);
FORCEPROP 2 LAST CDS_LIB standard
J 0
(-3250 1525);
DISPLAY INVISIBLE (-3250 1525);
FORCEPROP 1 LAST COMMENT_BODY TRUE
J 0
(-3125 1425);
DISPLAY 0.872340 (-3125 1425);
PAINT GREEN (-3125 1425);
DISPLAY INVISIBLE (-3125 1425);
FORCEPROP 1 LAST OFFPAGE TRUE
J 0
(-2925 1400);
DISPLAY 0.872340 (-2925 1400);
PAINT AQUA (-2925 1400);
DISPLAY INVISIBLE (-2925 1400);
FORCEADD OFFPAGE..1
(-3250 1575);
FORCEPROP 2 LAST $XR0 173 
J 0
(-3502 1575);
DISPLAY 0.638298 (-3502 1575);
PAINT MONO (-3502 1575);
FORCEPROP 2 LAST PATH I34
J 0
(-3500 1625);
DISPLAY 1.021277 (-3500 1625);
DISPLAY INVISIBLE (-3500 1625);
FORCEPROP 1 LAST OFFPAGE TRUE
J 0
(-2925 1450);
DISPLAY 0.872340 (-2925 1450);
PAINT AQUA (-2925 1450);
DISPLAY INVISIBLE (-2925 1450);
FORCEPROP 1 LAST COMMENT_BODY TRUE
J 0
(-3125 1475);
DISPLAY 0.872340 (-3125 1475);
PAINT GREEN (-3125 1475);
DISPLAY INVISIBLE (-3125 1475);
FORCEPROP 2 LAST CDS_LIB standard
J 0
(-3250 1575);
DISPLAY INVISIBLE (-3250 1575);
FORCEADD OFFPAGE..2
R 2
(-3250 1725);
FORCEPROP 2 LAST $XR0 31 
J 0
(-3504 1725);
DISPLAY 0.638298 (-3504 1725);
PAINT MONO (-3504 1725);
FORCEPROP 2 LAST PATH I35
J 0
(-3500 1775);
DISPLAY 1.021277 (-3500 1775);
DISPLAY INVISIBLE (-3500 1775);
FORCEPROP 1 LAST OFFPAGE TRUE
J 2
(-3575 1600);
DISPLAY 0.872340 (-3575 1600);
PAINT AQUA (-3575 1600);
DISPLAY INVISIBLE (-3575 1600);
FORCEPROP 1 LAST COMMENT_BODY TRUE
J 2
(-3205 1630);
DISPLAY 0.872340 (-3205 1630);
PAINT GREEN (-3205 1630);
DISPLAY INVISIBLE (-3205 1630);
FORCEPROP 2 LAST CDS_LIB standard
J 0
(-3250 1725);
DISPLAY INVISIBLE (-3250 1725);
FORCEADD OFFPAGE..5
(-3250 1825);
FORCEPROP 2 LAST $XR0 29 
J 0
(-3504 1825);
DISPLAY 0.638298 (-3504 1825);
PAINT MONO (-3504 1825);
FORCEPROP 2 LAST PATH I36
J 0
(-3500 1875);
DISPLAY 1.021277 (-3500 1875);
DISPLAY INVISIBLE (-3500 1875);
FORCEPROP 2 LAST CDS_LIB standard
J 0
(-3250 1825);
DISPLAY INVISIBLE (-3250 1825);
FORCEPROP 1 LAST COMMENT_BODY TRUE
J 0
(-3150 1750);
DISPLAY 1.170213 (-3150 1750);
PAINT GREEN (-3150 1750);
DISPLAY INVISIBLE (-3150 1750);
FORCEPROP 1 LAST OFFPAGE TRUE
J 0
(-2925 1700);
DISPLAY 0.872340 (-2925 1700);
PAINT AQUA (-2925 1700);
DISPLAY INVISIBLE (-2925 1700);
FORCEADD OFFPAGE..2
R 2
(-3250 1875);
FORCEPROP 2 LAST $XR0 29 
J 0
(-3504 1875);
DISPLAY 0.638298 (-3504 1875);
PAINT MONO (-3504 1875);
FORCEPROP 2 LAST PATH I37
J 0
(-3500 1925);
DISPLAY 1.021277 (-3500 1925);
DISPLAY INVISIBLE (-3500 1925);
FORCEPROP 2 LAST CDS_LIB standard
J 0
(-3250 1875);
DISPLAY INVISIBLE (-3250 1875);
FORCEPROP 1 LAST COMMENT_BODY TRUE
J 2
(-3205 1780);
DISPLAY 0.872340 (-3205 1780);
PAINT GREEN (-3205 1780);
DISPLAY INVISIBLE (-3205 1780);
FORCEPROP 1 LAST OFFPAGE TRUE
J 2
(-3575 1750);
DISPLAY 0.872340 (-3575 1750);
PAINT AQUA (-3575 1750);
DISPLAY INVISIBLE (-3575 1750);
FORCEADD OFFPAGE..1
(1275 -1075);
FORCEPROP 2 LAST $XR0 175 
J 0
(1023 -1075);
DISPLAY 0.638298 (1023 -1075);
PAINT MONO (1023 -1075);
FORCEPROP 2 LAST CDS_LIB standard
J 0
(1275 -1075);
DISPLAY INVISIBLE (1275 -1075);
FORCEPROP 1 LAST COMMENT_BODY TRUE
J 0
(1400 -1175);
DISPLAY 0.872340 (1400 -1175);
PAINT GREEN (1400 -1175);
DISPLAY INVISIBLE (1400 -1175);
FORCEPROP 1 LAST OFFPAGE TRUE
J 0
(1600 -1200);
DISPLAY 0.872340 (1600 -1200);
PAINT AQUA (1600 -1200);
DISPLAY INVISIBLE (1600 -1200);
FORCEPROP 2 LAST PATH I38
J 0
(1025 -1025);
DISPLAY 1.021277 (1025 -1025);
DISPLAY INVISIBLE (1025 -1025);
FORCEADD OFFPAGE..1
(1275 -1125);
FORCEPROP 2 LAST $XR0 175 
J 0
(1023 -1125);
DISPLAY 0.638298 (1023 -1125);
PAINT MONO (1023 -1125);
FORCEPROP 2 LAST CDS_LIB standard
J 0
(1275 -1125);
DISPLAY INVISIBLE (1275 -1125);
FORCEPROP 1 LAST COMMENT_BODY TRUE
J 0
(1400 -1225);
DISPLAY 0.872340 (1400 -1225);
PAINT GREEN (1400 -1225);
DISPLAY INVISIBLE (1400 -1225);
FORCEPROP 1 LAST OFFPAGE TRUE
J 0
(1600 -1250);
DISPLAY 0.872340 (1600 -1250);
PAINT AQUA (1600 -1250);
DISPLAY INVISIBLE (1600 -1250);
FORCEPROP 2 LAST PATH I39
J 0
(1025 -1075);
DISPLAY 1.021277 (1025 -1075);
DISPLAY INVISIBLE (1025 -1075);
FORCEADD OFFPAGE..1
(-3250 -875);
FORCEPROP 2 LAST $XR0 173 
J 0
(-3502 -875);
DISPLAY 0.638298 (-3502 -875);
PAINT MONO (-3502 -875);
FORCEPROP 2 LAST PATH I4
J 0
(-3500 -825);
DISPLAY 1.021277 (-3500 -825);
DISPLAY INVISIBLE (-3500 -825);
FORCEPROP 1 LAST OFFPAGE TRUE
J 0
(-2925 -1000);
DISPLAY 0.872340 (-2925 -1000);
PAINT AQUA (-2925 -1000);
DISPLAY INVISIBLE (-2925 -1000);
FORCEPROP 1 LAST COMMENT_BODY TRUE
J 0
(-3125 -975);
DISPLAY 0.872340 (-3125 -975);
PAINT GREEN (-3125 -975);
DISPLAY INVISIBLE (-3125 -975);
FORCEPROP 2 LAST CDS_LIB standard
J 0
(-3250 -875);
DISPLAY INVISIBLE (-3250 -875);
FORCEADD OFFPAGE..1
(1275 -975);
FORCEPROP 2 LAST $XR0 173 
J 0
(1023 -975);
DISPLAY 0.638298 (1023 -975);
PAINT MONO (1023 -975);
FORCEPROP 1 LAST OFFPAGE TRUE
J 0
(1600 -1100);
DISPLAY 0.872340 (1600 -1100);
PAINT AQUA (1600 -1100);
DISPLAY INVISIBLE (1600 -1100);
FORCEPROP 1 LAST COMMENT_BODY TRUE
J 0
(1400 -1075);
DISPLAY 0.872340 (1400 -1075);
PAINT GREEN (1400 -1075);
DISPLAY INVISIBLE (1400 -1075);
FORCEPROP 2 LAST CDS_LIB standard
J 0
(1275 -975);
DISPLAY INVISIBLE (1275 -975);
FORCEPROP 2 LAST PATH I40
J 0
(1025 -925);
DISPLAY 1.021277 (1025 -925);
DISPLAY INVISIBLE (1025 -925);
FORCEADD OFFPAGE..1
(1275 -925);
FORCEPROP 2 LAST $XR0 173 
J 0
(1023 -925);
DISPLAY 0.638298 (1023 -925);
PAINT MONO (1023 -925);
FORCEPROP 1 LAST OFFPAGE TRUE
J 0
(1600 -1050);
DISPLAY 0.872340 (1600 -1050);
PAINT AQUA (1600 -1050);
DISPLAY INVISIBLE (1600 -1050);
FORCEPROP 1 LAST COMMENT_BODY TRUE
J 0
(1400 -1025);
DISPLAY 0.872340 (1400 -1025);
PAINT GREEN (1400 -1025);
DISPLAY INVISIBLE (1400 -1025);
FORCEPROP 2 LAST CDS_LIB standard
J 0
(1275 -925);
DISPLAY INVISIBLE (1275 -925);
FORCEPROP 2 LAST PATH I41
J 0
(1025 -875);
DISPLAY 1.021277 (1025 -875);
DISPLAY INVISIBLE (1025 -875);
FORCEADD OFFPAGE..2
R 2
(1275 -775);
FORCEPROP 2 LAST $XR0 31 
J 0
(1021 -775);
DISPLAY 0.638298 (1021 -775);
PAINT MONO (1021 -775);
FORCEPROP 2 LAST CDS_LIB standard
J 0
(1275 -775);
DISPLAY INVISIBLE (1275 -775);
FORCEPROP 1 LAST COMMENT_BODY TRUE
J 2
(1320 -870);
DISPLAY 0.872340 (1320 -870);
PAINT GREEN (1320 -870);
DISPLAY INVISIBLE (1320 -870);
FORCEPROP 1 LAST OFFPAGE TRUE
J 2
(950 -900);
DISPLAY 0.872340 (950 -900);
PAINT AQUA (950 -900);
DISPLAY INVISIBLE (950 -900);
FORCEPROP 2 LAST PATH I42
J 0
(1025 -725);
DISPLAY 1.021277 (1025 -725);
DISPLAY INVISIBLE (1025 -725);
FORCEADD OFFPAGE..5
(1275 -675);
FORCEPROP 2 LAST $XR0 29 
J 0
(1021 -675);
DISPLAY 0.638298 (1021 -675);
PAINT MONO (1021 -675);
FORCEPROP 2 LAST CDS_LIB standard
J 0
(1275 -675);
DISPLAY INVISIBLE (1275 -675);
FORCEPROP 1 LAST COMMENT_BODY TRUE
J 0
(1375 -750);
DISPLAY 1.170213 (1375 -750);
PAINT GREEN (1375 -750);
DISPLAY INVISIBLE (1375 -750);
FORCEPROP 1 LAST OFFPAGE TRUE
J 0
(1600 -800);
DISPLAY 0.872340 (1600 -800);
PAINT AQUA (1600 -800);
DISPLAY INVISIBLE (1600 -800);
FORCEPROP 2 LAST PATH I43
J 0
(1025 -625);
DISPLAY 1.021277 (1025 -625);
DISPLAY INVISIBLE (1025 -625);
FORCEADD OFFPAGE..5
(1275 -825);
FORCEPROP 2 LAST $XR0 31 
J 0
(1021 -825);
DISPLAY 0.638298 (1021 -825);
PAINT MONO (1021 -825);
FORCEPROP 2 LAST CDS_LIB standard
J 0
(1275 -825);
DISPLAY INVISIBLE (1275 -825);
FORCEPROP 1 LAST COMMENT_BODY TRUE
J 0
(1375 -900);
DISPLAY 1.170213 (1375 -900);
PAINT GREEN (1375 -900);
DISPLAY INVISIBLE (1375 -900);
FORCEPROP 1 LAST OFFPAGE TRUE
J 0
(1600 -950);
DISPLAY 0.872340 (1600 -950);
PAINT AQUA (1600 -950);
DISPLAY INVISIBLE (1600 -950);
FORCEPROP 2 LAST PATH I44
J 0
(1025 -775);
DISPLAY 1.021277 (1025 -775);
DISPLAY INVISIBLE (1025 -775);
FORCEADD OFFPAGE..2
R 2
(1275 -625);
FORCEPROP 2 LAST $XR0 29 
J 0
(1021 -625);
DISPLAY 0.638298 (1021 -625);
PAINT MONO (1021 -625);
FORCEPROP 2 LAST CDS_LIB standard
J 0
(1275 -625);
DISPLAY INVISIBLE (1275 -625);
FORCEPROP 1 LAST COMMENT_BODY TRUE
J 2
(1320 -720);
DISPLAY 0.872340 (1320 -720);
PAINT GREEN (1320 -720);
DISPLAY INVISIBLE (1320 -720);
FORCEPROP 1 LAST OFFPAGE TRUE
J 2
(950 -750);
DISPLAY 0.872340 (950 -750);
PAINT AQUA (950 -750);
DISPLAY INVISIBLE (950 -750);
FORCEPROP 2 LAST PATH I45
J 0
(1025 -575);
DISPLAY 1.021277 (1025 -575);
DISPLAY INVISIBLE (1025 -575);
FORCEADD OFFPAGE..1
(1275 -225);
FORCEPROP 2 LAST $XR0 175 
J 0
(1023 -225);
DISPLAY 0.638298 (1023 -225);
PAINT MONO (1023 -225);
FORCEPROP 2 LAST CDS_LIB standard
J 0
(1275 -225);
DISPLAY INVISIBLE (1275 -225);
FORCEPROP 1 LAST COMMENT_BODY TRUE
J 0
(1400 -325);
DISPLAY 0.872340 (1400 -325);
PAINT GREEN (1400 -325);
DISPLAY INVISIBLE (1400 -325);
FORCEPROP 1 LAST OFFPAGE TRUE
J 0
(1600 -350);
DISPLAY 0.872340 (1600 -350);
PAINT AQUA (1600 -350);
DISPLAY INVISIBLE (1600 -350);
FORCEPROP 2 LAST PATH I47
J 0
(1025 -175);
DISPLAY 1.021277 (1025 -175);
DISPLAY INVISIBLE (1025 -175);
FORCEADD OFFPAGE..1
(1275 -275);
FORCEPROP 2 LAST $XR0 175 
J 0
(1023 -275);
DISPLAY 0.638298 (1023 -275);
PAINT MONO (1023 -275);
FORCEPROP 2 LAST CDS_LIB standard
J 0
(1275 -275);
DISPLAY INVISIBLE (1275 -275);
FORCEPROP 1 LAST COMMENT_BODY TRUE
J 0
(1400 -375);
DISPLAY 0.872340 (1400 -375);
PAINT GREEN (1400 -375);
DISPLAY INVISIBLE (1400 -375);
FORCEPROP 1 LAST OFFPAGE TRUE
J 0
(1600 -400);
DISPLAY 0.872340 (1600 -400);
PAINT AQUA (1600 -400);
DISPLAY INVISIBLE (1600 -400);
FORCEPROP 2 LAST PATH I48
J 0
(1025 -225);
DISPLAY 1.021277 (1025 -225);
DISPLAY INVISIBLE (1025 -225);
FORCEADD OFFPAGE..2
R 2
(-3250 -725);
FORCEPROP 2 LAST $XR0 31 
J 0
(-3504 -725);
DISPLAY 0.638298 (-3504 -725);
PAINT MONO (-3504 -725);
FORCEPROP 2 LAST PATH I5
J 0
(-3500 -675);
DISPLAY 1.021277 (-3500 -675);
DISPLAY INVISIBLE (-3500 -675);
FORCEPROP 2 LAST CDS_LIB standard
J 0
(-3250 -725);
DISPLAY INVISIBLE (-3250 -725);
FORCEPROP 1 LAST COMMENT_BODY TRUE
J 2
(-3205 -820);
DISPLAY 0.872340 (-3205 -820);
PAINT GREEN (-3205 -820);
DISPLAY INVISIBLE (-3205 -820);
FORCEPROP 1 LAST OFFPAGE TRUE
J 2
(-3575 -850);
DISPLAY 0.872340 (-3575 -850);
PAINT AQUA (-3575 -850);
DISPLAY INVISIBLE (-3575 -850);
FORCEADD OFFPAGE..1
(1275 -125);
FORCEPROP 2 LAST $XR0 173 
J 0
(1023 -125);
DISPLAY 0.638298 (1023 -125);
PAINT MONO (1023 -125);
FORCEPROP 1 LAST OFFPAGE TRUE
J 0
(1600 -250);
DISPLAY 0.872340 (1600 -250);
PAINT AQUA (1600 -250);
DISPLAY INVISIBLE (1600 -250);
FORCEPROP 1 LAST COMMENT_BODY TRUE
J 0
(1400 -225);
DISPLAY 0.872340 (1400 -225);
PAINT GREEN (1400 -225);
DISPLAY INVISIBLE (1400 -225);
FORCEPROP 2 LAST CDS_LIB standard
J 0
(1275 -125);
DISPLAY INVISIBLE (1275 -125);
FORCEPROP 2 LAST PATH I50
J 0
(1025 -75);
DISPLAY 1.021277 (1025 -75);
DISPLAY INVISIBLE (1025 -75);
FORCEADD OFFPAGE..1
(1275 -75);
FORCEPROP 2 LAST $XR0 173 
J 0
(1023 -75);
DISPLAY 0.638298 (1023 -75);
PAINT MONO (1023 -75);
FORCEPROP 1 LAST OFFPAGE TRUE
J 0
(1600 -200);
DISPLAY 0.872340 (1600 -200);
PAINT AQUA (1600 -200);
DISPLAY INVISIBLE (1600 -200);
FORCEPROP 1 LAST COMMENT_BODY TRUE
J 0
(1400 -175);
DISPLAY 0.872340 (1400 -175);
PAINT GREEN (1400 -175);
DISPLAY INVISIBLE (1400 -175);
FORCEPROP 2 LAST CDS_LIB standard
J 0
(1275 -75);
DISPLAY INVISIBLE (1275 -75);
FORCEPROP 2 LAST PATH I51
J 0
(1025 -25);
DISPLAY 1.021277 (1025 -25);
DISPLAY INVISIBLE (1025 -25);
FORCEADD OFFPAGE..2
R 2
(1275 75);
FORCEPROP 2 LAST $XR0 31 
J 0
(1021 75);
DISPLAY 0.638298 (1021 75);
PAINT MONO (1021 75);
FORCEPROP 2 LAST CDS_LIB standard
J 0
(1275 75);
DISPLAY INVISIBLE (1275 75);
FORCEPROP 1 LAST COMMENT_BODY TRUE
J 2
(1320 -20);
DISPLAY 0.872340 (1320 -20);
PAINT GREEN (1320 -20);
DISPLAY INVISIBLE (1320 -20);
FORCEPROP 1 LAST OFFPAGE TRUE
J 2
(950 -50);
DISPLAY 0.872340 (950 -50);
PAINT AQUA (950 -50);
DISPLAY INVISIBLE (950 -50);
FORCEPROP 2 LAST PATH I52
J 0
(1025 125);
DISPLAY 1.021277 (1025 125);
DISPLAY INVISIBLE (1025 125);
FORCEADD OFFPAGE..5
(1275 25);
FORCEPROP 2 LAST $XR0 31 
J 0
(1021 25);
DISPLAY 0.638298 (1021 25);
PAINT MONO (1021 25);
FORCEPROP 2 LAST CDS_LIB standard
J 0
(1275 25);
DISPLAY INVISIBLE (1275 25);
FORCEPROP 1 LAST COMMENT_BODY TRUE
J 0
(1375 -50);
DISPLAY 1.170213 (1375 -50);
PAINT GREEN (1375 -50);
DISPLAY INVISIBLE (1375 -50);
FORCEPROP 1 LAST OFFPAGE TRUE
J 0
(1600 -100);
DISPLAY 0.872340 (1600 -100);
PAINT AQUA (1600 -100);
DISPLAY INVISIBLE (1600 -100);
FORCEPROP 2 LAST PATH I53
J 0
(1025 75);
DISPLAY 1.021277 (1025 75);
DISPLAY INVISIBLE (1025 75);
FORCEADD OFFPAGE..2
R 2
(1275 225);
FORCEPROP 2 LAST $XR0 29 
J 0
(1021 225);
DISPLAY 0.638298 (1021 225);
PAINT MONO (1021 225);
FORCEPROP 1 LAST OFFPAGE TRUE
J 2
(950 100);
DISPLAY 0.872340 (950 100);
PAINT AQUA (950 100);
DISPLAY INVISIBLE (950 100);
FORCEPROP 1 LAST COMMENT_BODY TRUE
J 2
(1320 130);
DISPLAY 0.872340 (1320 130);
PAINT GREEN (1320 130);
DISPLAY INVISIBLE (1320 130);
FORCEPROP 2 LAST CDS_LIB standard
J 0
(1275 225);
DISPLAY INVISIBLE (1275 225);
FORCEPROP 2 LAST PATH I54
J 0
(1025 275);
DISPLAY 1.021277 (1025 275);
DISPLAY INVISIBLE (1025 275);
FORCEADD OFFPAGE..5
(1275 175);
FORCEPROP 2 LAST $XR0 29 
J 0
(1021 175);
DISPLAY 0.638298 (1021 175);
PAINT MONO (1021 175);
FORCEPROP 1 LAST OFFPAGE TRUE
J 0
(1600 50);
DISPLAY 0.872340 (1600 50);
PAINT AQUA (1600 50);
DISPLAY INVISIBLE (1600 50);
FORCEPROP 1 LAST COMMENT_BODY TRUE
J 0
(1375 100);
DISPLAY 1.170213 (1375 100);
PAINT GREEN (1375 100);
DISPLAY INVISIBLE (1375 100);
FORCEPROP 2 LAST CDS_LIB standard
J 0
(1275 175);
DISPLAY INVISIBLE (1275 175);
FORCEPROP 2 LAST PATH I55
J 0
(1025 225);
DISPLAY 1.021277 (1025 225);
DISPLAY INVISIBLE (1025 225);
FORCEADD UNIVERSAL_GND..1
(2350 -1575);
FORCEPROP 3 LASTPIN (2350 -1525) SIG_NAME GND\g
J 0
(2360 -1515);
DISPLAY 0.659574 (2360 -1515);
PAINT MONO (2360 -1515);
DISPLAY INVISIBLE (2360 -1515);
FORCEPROP 1 LAST HDL_POWER GND
J 1
(2375 -1650);
DISPLAY 0.872340 (2375 -1650);
PAINT GREEN (2375 -1650);
DISPLAY INVISIBLE (2375 -1650);
FORCEPROP 2 LAST CDS_LIB logical_power
J 0
(2350 -1575);
DISPLAY INVISIBLE (2350 -1575);
FORCEPROP 1 LAST PATH I56
J 0
(2425 -1575);
DISPLAY 0.872340 (2425 -1575);
PAINT AQUA (2425 -1575);
DISPLAY INVISIBLE (2425 -1575);
FORCEADD CONN112_10137002101LF..2
(3500 375);
FORCEPROP 1 LAST PART_NUMBER DFHSB2FR012
J 0
(2750 2150);
DISPLAY 0.723404 (2750 2150);
PAINT GREEN (2750 2150);
DISPLAY INVISIBLE (2750 2150);
FORCEPROP 2 LAST PART_TYPE THLF
J 0
(2750 2275);
DISPLAY 1.021277 (2750 2275);
FORCEPROP 1 LAST MATERIAL IO
J 0
(2758 2088);
DISPLAY 0.723404 (2758 2088);
PAINT GREEN (2758 2088);
FORCEPROP 1 LAST LOCATION J108
J 0
(2750 2200);
DISPLAY 0.723404 (2750 2200);
PAINT GREEN (2750 2200);
FORCEPROP 0 LASTPIN (2575 -525) $PN A1
J 2
(2565 -515);
DISPLAY 0.680851 (2565 -515);
PAINT MONO (2565 -515);
FORCEPROP 0 LASTPIN (2575 275) $PN A2
J 2
(2565 285);
DISPLAY 0.680851 (2565 285);
PAINT MONO (2565 285);
FORCEPROP 0 LASTPIN (2575 1075) $PN A3
J 2
(2565 1085);
DISPLAY 0.680851 (2565 1085);
PAINT MONO (2565 1085);
FORCEPROP 0 LASTPIN (2575 1875) $PN A4
J 2
(2565 1885);
DISPLAY 0.680851 (2565 1885);
PAINT MONO (2565 1885);
FORCEPROP 0 LASTPIN (2575 -575) $PN B1
J 2
(2565 -565);
DISPLAY 0.680851 (2565 -565);
PAINT MONO (2565 -565);
FORCEPROP 0 LASTPIN (2575 225) $PN B2
J 2
(2565 235);
DISPLAY 0.680851 (2565 235);
PAINT MONO (2565 235);
FORCEPROP 0 LASTPIN (2575 1025) $PN B3
J 2
(2565 1035);
DISPLAY 0.680851 (2565 1035);
PAINT MONO (2565 1035);
FORCEPROP 0 LASTPIN (2575 1825) $PN B4
J 2
(2565 1835);
DISPLAY 0.680851 (2565 1835);
PAINT MONO (2565 1835);
FORCEPROP 0 LASTPIN (2575 -625) $PN C1
J 2
(2565 -615);
DISPLAY 0.680851 (2565 -615);
PAINT MONO (2565 -615);
FORCEPROP 0 LASTPIN (2575 175) $PN C2
J 2
(2565 185);
DISPLAY 0.680851 (2565 185);
PAINT MONO (2565 185);
FORCEPROP 0 LASTPIN (2575 975) $PN C3
J 2
(2565 985);
DISPLAY 0.680851 (2565 985);
PAINT MONO (2565 985);
FORCEPROP 0 LASTPIN (2575 1775) $PN C4
J 2
(2565 1785);
DISPLAY 0.680851 (2565 1785);
PAINT MONO (2565 1785);
FORCEPROP 0 LASTPIN (2575 -675) $PN D1
J 2
(2565 -665);
DISPLAY 0.680851 (2565 -665);
PAINT MONO (2565 -665);
FORCEPROP 0 LASTPIN (2575 125) $PN D2
J 2
(2565 135);
DISPLAY 0.680851 (2565 135);
PAINT MONO (2565 135);
FORCEPROP 0 LASTPIN (2575 925) $PN D3
J 2
(2565 935);
DISPLAY 0.680851 (2565 935);
PAINT MONO (2565 935);
FORCEPROP 0 LASTPIN (2575 1725) $PN D4
J 2
(2565 1735);
DISPLAY 0.680851 (2565 1735);
PAINT MONO (2565 1735);
FORCEPROP 0 LASTPIN (2575 -725) $PN E1
J 2
(2565 -715);
DISPLAY 0.680851 (2565 -715);
PAINT MONO (2565 -715);
FORCEPROP 0 LASTPIN (2575 75) $PN E2
J 2
(2565 85);
DISPLAY 0.680851 (2565 85);
PAINT MONO (2565 85);
FORCEPROP 0 LASTPIN (2575 875) $PN E3
J 2
(2565 885);
DISPLAY 0.680851 (2565 885);
PAINT MONO (2565 885);
FORCEPROP 0 LASTPIN (2575 1675) $PN E4
J 2
(2565 1685);
DISPLAY 0.680851 (2565 1685);
PAINT MONO (2565 1685);
FORCEPROP 0 LASTPIN (2575 -775) $PN F1
J 2
(2565 -765);
DISPLAY 0.680851 (2565 -765);
PAINT MONO (2565 -765);
FORCEPROP 0 LASTPIN (2575 25) $PN F2
J 2
(2565 35);
DISPLAY 0.680851 (2565 35);
PAINT MONO (2565 35);
FORCEPROP 0 LASTPIN (2575 825) $PN F3
J 2
(2565 835);
DISPLAY 0.680851 (2565 835);
PAINT MONO (2565 835);
FORCEPROP 0 LASTPIN (2575 1625) $PN F4
J 2
(2565 1635);
DISPLAY 0.680851 (2565 1635);
PAINT MONO (2565 1635);
FORCEPROP 0 LASTPIN (2575 -825) $PN G1
J 2
(2565 -815);
DISPLAY 0.680851 (2565 -815);
PAINT MONO (2565 -815);
FORCEPROP 0 LASTPIN (2575 -25) $PN G2
J 2
(2565 -15);
DISPLAY 0.680851 (2565 -15);
PAINT MONO (2565 -15);
FORCEPROP 0 LASTPIN (2575 775) $PN G3
J 2
(2565 785);
DISPLAY 0.680851 (2565 785);
PAINT MONO (2565 785);
FORCEPROP 0 LASTPIN (2575 1575) $PN G4
J 2
(2565 1585);
DISPLAY 0.680851 (2565 1585);
PAINT MONO (2565 1585);
FORCEPROP 0 LASTPIN (2575 -875) $PN H1
J 2
(2565 -865);
DISPLAY 0.680851 (2565 -865);
PAINT MONO (2565 -865);
FORCEPROP 0 LASTPIN (2575 -75) $PN H2
J 2
(2565 -65);
DISPLAY 0.680851 (2565 -65);
PAINT MONO (2565 -65);
FORCEPROP 0 LASTPIN (2575 725) $PN H3
J 2
(2565 735);
DISPLAY 0.680851 (2565 735);
PAINT MONO (2565 735);
FORCEPROP 0 LASTPIN (2575 1525) $PN H4
J 2
(2565 1535);
DISPLAY 0.680851 (2565 1535);
PAINT MONO (2565 1535);
FORCEPROP 0 LASTPIN (2575 -925) $PN I1
J 2
(2565 -915);
DISPLAY 0.680851 (2565 -915);
PAINT MONO (2565 -915);
FORCEPROP 0 LASTPIN (2575 -125) $PN I2
J 2
(2565 -115);
DISPLAY 0.680851 (2565 -115);
PAINT MONO (2565 -115);
FORCEPROP 0 LASTPIN (2575 675) $PN I3
J 2
(2565 685);
DISPLAY 0.680851 (2565 685);
PAINT MONO (2565 685);
FORCEPROP 0 LASTPIN (2575 1475) $PN I4
J 2
(2565 1485);
DISPLAY 0.680851 (2565 1485);
PAINT MONO (2565 1485);
FORCEPROP 0 LASTPIN (2575 -975) $PN J1
J 2
(2565 -965);
DISPLAY 0.680851 (2565 -965);
PAINT MONO (2565 -965);
FORCEPROP 0 LASTPIN (2575 -175) $PN J2
J 2
(2565 -165);
DISPLAY 0.680851 (2565 -165);
PAINT MONO (2565 -165);
FORCEPROP 0 LASTPIN (2575 625) $PN J3
J 2
(2565 635);
DISPLAY 0.680851 (2565 635);
PAINT MONO (2565 635);
FORCEPROP 0 LASTPIN (2575 1425) $PN J4
J 2
(2565 1435);
DISPLAY 0.680851 (2565 1435);
PAINT MONO (2565 1435);
FORCEPROP 0 LASTPIN (2575 -1025) $PN K1
J 2
(2565 -1015);
DISPLAY 0.680851 (2565 -1015);
PAINT MONO (2565 -1015);
FORCEPROP 0 LASTPIN (2575 -225) $PN K2
J 2
(2565 -215);
DISPLAY 0.680851 (2565 -215);
PAINT MONO (2565 -215);
FORCEPROP 0 LASTPIN (2575 575) $PN K3
J 2
(2565 585);
DISPLAY 0.680851 (2565 585);
PAINT MONO (2565 585);
FORCEPROP 0 LASTPIN (2575 1375) $PN K4
J 2
(2565 1385);
DISPLAY 0.680851 (2565 1385);
PAINT MONO (2565 1385);
FORCEPROP 0 LASTPIN (2575 -1075) $PN L1
J 2
(2565 -1065);
DISPLAY 0.680851 (2565 -1065);
PAINT MONO (2565 -1065);
FORCEPROP 0 LASTPIN (2575 -275) $PN L2
J 2
(2565 -265);
DISPLAY 0.680851 (2565 -265);
PAINT MONO (2565 -265);
FORCEPROP 0 LASTPIN (2575 525) $PN L3
J 2
(2565 535);
DISPLAY 0.680851 (2565 535);
PAINT MONO (2565 535);
FORCEPROP 0 LASTPIN (2575 1325) $PN L4
J 2
(2565 1335);
DISPLAY 0.680851 (2565 1335);
PAINT MONO (2565 1335);
FORCEPROP 0 LASTPIN (2575 -1125) $PN M1
J 2
(2565 -1115);
DISPLAY 0.680851 (2565 -1115);
PAINT MONO (2565 -1115);
FORCEPROP 0 LASTPIN (2575 -325) $PN M2
J 2
(2565 -315);
DISPLAY 0.680851 (2565 -315);
PAINT MONO (2565 -315);
FORCEPROP 0 LASTPIN (2575 475) $PN M3
J 2
(2565 485);
DISPLAY 0.680851 (2565 485);
PAINT MONO (2565 485);
FORCEPROP 0 LASTPIN (2575 1275) $PN M4
J 2
(2565 1285);
DISPLAY 0.680851 (2565 1285);
PAINT MONO (2565 1285);
FORCEPROP 0 LASTPIN (2575 -1175) $PN N1
J 2
(2565 -1165);
DISPLAY 0.680851 (2565 -1165);
PAINT MONO (2565 -1165);
FORCEPROP 0 LASTPIN (2575 -375) $PN N2
J 2
(2565 -365);
DISPLAY 0.680851 (2565 -365);
PAINT MONO (2565 -365);
FORCEPROP 0 LASTPIN (2575 425) $PN N3
J 2
(2565 435);
DISPLAY 0.680851 (2565 435);
PAINT MONO (2565 435);
FORCEPROP 0 LASTPIN (2575 1225) $PN N4
J 2
(2565 1235);
DISPLAY 0.680851 (2565 1235);
PAINT MONO (2565 1235);
FORCEPROP 1 LAST CDS_LMAN_SYM_OUTLINE -775,1650,775,-1650
J 0
(3500 375);
DISPLAY 0.468085 (3500 375);
PAINT GREEN (3500 375);
DISPLAY INVISIBLE (3500 375);
FORCEPROP 1 LAST NEEDS_NO_SIZE TRUE
J 0
(3500 375);
DISPLAY 0.723404 (3500 375);
PAINT GREEN (3500 375);
DISPLAY INVISIBLE (3500 375);
FORCEPROP 2 LAST CDS_LIB pure_quanta
J 0
(3500 375);
DISPLAY INVISIBLE (3500 375);
FORCEPROP 0 LAST VALUE CONN112_10137002-101LF
J 0
(2750 2275);
DISPLAY 1.021277 (2750 2275);
DISPLAY INVISIBLE (2750 2275);
FORCEPROP 1 LAST PATH I57
J 0
(3500 375);
DISPLAY 0.723404 (3500 375);
PAINT GREEN (3500 375);
DISPLAY INVISIBLE (3500 375);
FORCEPROP 0 LAST $SEC 2
J 0
(2750 2325);
DISPLAY 0.680851 (2750 2325);
PAINT MONO (2750 2325);
DISPLAY INVISIBLE (2750 2325);
FORCEPROP 0 LAST CDS_SEC 2
J 0
(2750 2325);
DISPLAY 1.021277 (2750 2325);
DISPLAY INVISIBLE (2750 2325);
FORCEADD OFFPAGE..1
(1275 525);
FORCEPROP 2 LAST $XR0 175 
J 0
(1023 525);
DISPLAY 0.638298 (1023 525);
PAINT MONO (1023 525);
FORCEPROP 1 LAST OFFPAGE TRUE
J 0
(1600 400);
DISPLAY 0.872340 (1600 400);
PAINT AQUA (1600 400);
DISPLAY INVISIBLE (1600 400);
FORCEPROP 1 LAST COMMENT_BODY TRUE
J 0
(1400 425);
DISPLAY 0.872340 (1400 425);
PAINT GREEN (1400 425);
DISPLAY INVISIBLE (1400 425);
FORCEPROP 2 LAST CDS_LIB standard
J 0
(1275 525);
DISPLAY INVISIBLE (1275 525);
FORCEPROP 2 LAST PATH I58
J 0
(1025 575);
DISPLAY 1.021277 (1025 575);
DISPLAY INVISIBLE (1025 575);
FORCEADD OFFPAGE..1
(1275 475);
FORCEPROP 2 LAST $XR0 175 
J 0
(1023 475);
DISPLAY 0.638298 (1023 475);
PAINT MONO (1023 475);
FORCEPROP 2 LAST CDS_LIB standard
J 0
(1275 475);
DISPLAY INVISIBLE (1275 475);
FORCEPROP 1 LAST COMMENT_BODY TRUE
J 0
(1400 375);
DISPLAY 0.872340 (1400 375);
PAINT GREEN (1400 375);
DISPLAY INVISIBLE (1400 375);
FORCEPROP 1 LAST OFFPAGE TRUE
J 0
(1600 350);
DISPLAY 0.872340 (1600 350);
PAINT AQUA (1600 350);
DISPLAY INVISIBLE (1600 350);
FORCEPROP 2 LAST PATH I59
J 0
(1025 525);
DISPLAY 1.021277 (1025 525);
DISPLAY INVISIBLE (1025 525);
FORCEADD OFFPAGE..5
(-3250 -775);
FORCEPROP 2 LAST $XR0 31 
J 0
(-3504 -775);
DISPLAY 0.638298 (-3504 -775);
PAINT MONO (-3504 -775);
FORCEPROP 2 LAST PATH I6
J 0
(-3500 -725);
DISPLAY 1.021277 (-3500 -725);
DISPLAY INVISIBLE (-3500 -725);
FORCEPROP 2 LAST CDS_LIB standard
J 0
(-3250 -775);
DISPLAY INVISIBLE (-3250 -775);
FORCEPROP 1 LAST COMMENT_BODY TRUE
J 0
(-3150 -850);
DISPLAY 1.170213 (-3150 -850);
PAINT GREEN (-3150 -850);
DISPLAY INVISIBLE (-3150 -850);
FORCEPROP 1 LAST OFFPAGE TRUE
J 0
(-2925 -900);
DISPLAY 0.872340 (-2925 -900);
PAINT AQUA (-2925 -900);
DISPLAY INVISIBLE (-2925 -900);
FORCEADD OFFPAGE..1
(1275 625);
FORCEPROP 2 LAST $XR0 173 
J 0
(1023 625);
DISPLAY 0.638298 (1023 625);
PAINT MONO (1023 625);
FORCEPROP 2 LAST CDS_LIB standard
J 0
(1275 625);
DISPLAY INVISIBLE (1275 625);
FORCEPROP 1 LAST COMMENT_BODY TRUE
J 0
(1400 525);
DISPLAY 0.872340 (1400 525);
PAINT GREEN (1400 525);
DISPLAY INVISIBLE (1400 525);
FORCEPROP 1 LAST OFFPAGE TRUE
J 0
(1600 500);
DISPLAY 0.872340 (1600 500);
PAINT AQUA (1600 500);
DISPLAY INVISIBLE (1600 500);
FORCEPROP 2 LAST PATH I60
J 0
(1025 675);
DISPLAY 1.021277 (1025 675);
DISPLAY INVISIBLE (1025 675);
FORCEADD OFFPAGE..1
(1275 675);
FORCEPROP 2 LAST $XR0 173 
J 0
(1023 675);
DISPLAY 0.638298 (1023 675);
PAINT MONO (1023 675);
FORCEPROP 1 LAST OFFPAGE TRUE
J 0
(1600 550);
DISPLAY 0.872340 (1600 550);
PAINT AQUA (1600 550);
DISPLAY INVISIBLE (1600 550);
FORCEPROP 1 LAST COMMENT_BODY TRUE
J 0
(1400 575);
DISPLAY 0.872340 (1400 575);
PAINT GREEN (1400 575);
DISPLAY INVISIBLE (1400 575);
FORCEPROP 2 LAST CDS_LIB standard
J 0
(1275 675);
DISPLAY INVISIBLE (1275 675);
FORCEPROP 2 LAST PATH I61
J 0
(1025 725);
DISPLAY 1.021277 (1025 725);
DISPLAY INVISIBLE (1025 725);
FORCEADD OFFPAGE..2
R 2
(1275 825);
FORCEPROP 2 LAST $XR0 31 
J 0
(1021 825);
DISPLAY 0.638298 (1021 825);
PAINT MONO (1021 825);
FORCEPROP 1 LAST OFFPAGE TRUE
J 2
(950 700);
DISPLAY 0.872340 (950 700);
PAINT AQUA (950 700);
DISPLAY INVISIBLE (950 700);
FORCEPROP 1 LAST COMMENT_BODY TRUE
J 2
(1320 730);
DISPLAY 0.872340 (1320 730);
PAINT GREEN (1320 730);
DISPLAY INVISIBLE (1320 730);
FORCEPROP 2 LAST CDS_LIB standard
J 0
(1275 825);
DISPLAY INVISIBLE (1275 825);
FORCEPROP 2 LAST PATH I62
J 0
(1025 875);
DISPLAY 1.021277 (1025 875);
DISPLAY INVISIBLE (1025 875);
FORCEADD OFFPAGE..5
(1275 775);
FORCEPROP 2 LAST $XR0 31 
J 0
(1021 775);
DISPLAY 0.638298 (1021 775);
PAINT MONO (1021 775);
FORCEPROP 1 LAST OFFPAGE TRUE
J 0
(1600 650);
DISPLAY 0.872340 (1600 650);
PAINT AQUA (1600 650);
DISPLAY INVISIBLE (1600 650);
FORCEPROP 1 LAST COMMENT_BODY TRUE
J 0
(1375 700);
DISPLAY 1.170213 (1375 700);
PAINT GREEN (1375 700);
DISPLAY INVISIBLE (1375 700);
FORCEPROP 2 LAST CDS_LIB standard
J 0
(1275 775);
DISPLAY INVISIBLE (1275 775);
FORCEPROP 2 LAST PATH I63
J 0
(1025 825);
DISPLAY 1.021277 (1025 825);
DISPLAY INVISIBLE (1025 825);
FORCEADD OFFPAGE..1
(1275 1325);
FORCEPROP 2 LAST $XR0 175 
J 0
(1023 1325);
DISPLAY 0.638298 (1023 1325);
PAINT MONO (1023 1325);
FORCEPROP 2 LAST CDS_LIB standard
J 0
(1275 1325);
DISPLAY INVISIBLE (1275 1325);
FORCEPROP 1 LAST COMMENT_BODY TRUE
J 0
(1400 1225);
DISPLAY 0.872340 (1400 1225);
PAINT GREEN (1400 1225);
DISPLAY INVISIBLE (1400 1225);
FORCEPROP 1 LAST OFFPAGE TRUE
J 0
(1600 1200);
DISPLAY 0.872340 (1600 1200);
PAINT AQUA (1600 1200);
DISPLAY INVISIBLE (1600 1200);
FORCEPROP 2 LAST PATH I65
J 0
(1025 1375);
DISPLAY 1.021277 (1025 1375);
DISPLAY INVISIBLE (1025 1375);
FORCEADD OFFPAGE..1
(1275 1375);
FORCEPROP 2 LAST $XR0 175 
J 0
(1023 1375);
DISPLAY 0.638298 (1023 1375);
PAINT MONO (1023 1375);
FORCEPROP 1 LAST OFFPAGE TRUE
J 0
(1600 1250);
DISPLAY 0.872340 (1600 1250);
PAINT AQUA (1600 1250);
DISPLAY INVISIBLE (1600 1250);
FORCEPROP 1 LAST COMMENT_BODY TRUE
J 0
(1400 1275);
DISPLAY 0.872340 (1400 1275);
PAINT GREEN (1400 1275);
DISPLAY INVISIBLE (1400 1275);
FORCEPROP 2 LAST CDS_LIB standard
J 0
(1275 1375);
DISPLAY INVISIBLE (1275 1375);
FORCEPROP 2 LAST PATH I67
J 0
(1025 1425);
DISPLAY 1.021277 (1025 1425);
DISPLAY INVISIBLE (1025 1425);
FORCEADD OFFPAGE..2
R 2
(1275 975);
FORCEPROP 2 LAST $XR0 29 
J 0
(1021 975);
DISPLAY 0.638298 (1021 975);
PAINT MONO (1021 975);
FORCEPROP 1 LAST OFFPAGE TRUE
J 2
(950 850);
DISPLAY 0.872340 (950 850);
PAINT AQUA (950 850);
DISPLAY INVISIBLE (950 850);
FORCEPROP 1 LAST COMMENT_BODY TRUE
J 2
(1320 880);
DISPLAY 0.872340 (1320 880);
PAINT GREEN (1320 880);
DISPLAY INVISIBLE (1320 880);
FORCEPROP 2 LAST CDS_LIB standard
J 0
(1275 975);
DISPLAY INVISIBLE (1275 975);
FORCEPROP 2 LAST PATH I68
J 0
(1025 1025);
DISPLAY 1.021277 (1025 1025);
DISPLAY INVISIBLE (1025 1025);
FORCEADD OFFPAGE..5
(1275 925);
FORCEPROP 2 LAST $XR0 29 
J 0
(1021 925);
DISPLAY 0.638298 (1021 925);
PAINT MONO (1021 925);
FORCEPROP 1 LAST OFFPAGE TRUE
J 0
(1600 800);
DISPLAY 0.872340 (1600 800);
PAINT AQUA (1600 800);
DISPLAY INVISIBLE (1600 800);
FORCEPROP 1 LAST COMMENT_BODY TRUE
J 0
(1375 850);
DISPLAY 1.170213 (1375 850);
PAINT GREEN (1375 850);
DISPLAY INVISIBLE (1375 850);
FORCEPROP 2 LAST CDS_LIB standard
J 0
(1275 925);
DISPLAY INVISIBLE (1275 925);
FORCEPROP 2 LAST PATH I69
J 0
(1025 975);
DISPLAY 1.021277 (1025 975);
DISPLAY INVISIBLE (1025 975);
FORCEADD OFFPAGE..5
(-3250 -625);
FORCEPROP 2 LAST $XR0 29 
J 0
(-3504 -625);
DISPLAY 0.638298 (-3504 -625);
PAINT MONO (-3504 -625);
FORCEPROP 2 LAST PATH I7
J 0
(-3500 -575);
DISPLAY 1.021277 (-3500 -575);
DISPLAY INVISIBLE (-3500 -575);
FORCEPROP 2 LAST CDS_LIB standard
J 0
(-3250 -625);
DISPLAY INVISIBLE (-3250 -625);
FORCEPROP 1 LAST COMMENT_BODY TRUE
J 0
(-3150 -700);
DISPLAY 1.170213 (-3150 -700);
PAINT GREEN (-3150 -700);
DISPLAY INVISIBLE (-3150 -700);
FORCEPROP 1 LAST OFFPAGE TRUE
J 0
(-2925 -750);
DISPLAY 0.872340 (-2925 -750);
PAINT AQUA (-2925 -750);
DISPLAY INVISIBLE (-2925 -750);
FORCEADD OFFPAGE..1
(1275 1475);
FORCEPROP 2 LAST $XR0 173 
J 0
(1023 1475);
DISPLAY 0.638298 (1023 1475);
PAINT MONO (1023 1475);
FORCEPROP 1 LAST OFFPAGE TRUE
J 0
(1600 1350);
DISPLAY 0.872340 (1600 1350);
PAINT AQUA (1600 1350);
DISPLAY INVISIBLE (1600 1350);
FORCEPROP 1 LAST COMMENT_BODY TRUE
J 0
(1400 1375);
DISPLAY 0.872340 (1400 1375);
PAINT GREEN (1400 1375);
DISPLAY INVISIBLE (1400 1375);
FORCEPROP 2 LAST CDS_LIB standard
J 0
(1275 1475);
DISPLAY INVISIBLE (1275 1475);
FORCEPROP 2 LAST PATH I70
J 0
(1025 1525);
DISPLAY 1.021277 (1025 1525);
DISPLAY INVISIBLE (1025 1525);
FORCEADD OFFPAGE..1
(1275 1525);
FORCEPROP 2 LAST $XR0 173 
J 0
(1023 1525);
DISPLAY 0.638298 (1023 1525);
PAINT MONO (1023 1525);
FORCEPROP 2 LAST CDS_LIB standard
J 0
(1275 1525);
DISPLAY INVISIBLE (1275 1525);
FORCEPROP 1 LAST COMMENT_BODY TRUE
J 0
(1400 1425);
DISPLAY 0.872340 (1400 1425);
PAINT GREEN (1400 1425);
DISPLAY INVISIBLE (1400 1425);
FORCEPROP 1 LAST OFFPAGE TRUE
J 0
(1600 1400);
DISPLAY 0.872340 (1600 1400);
PAINT AQUA (1600 1400);
DISPLAY INVISIBLE (1600 1400);
FORCEPROP 2 LAST PATH I71
J 0
(1025 1575);
DISPLAY 1.021277 (1025 1575);
DISPLAY INVISIBLE (1025 1575);
FORCEADD OFFPAGE..5
(1275 1775);
FORCEPROP 2 LAST $XR0 29 
J 0
(1021 1775);
DISPLAY 0.638298 (1021 1775);
PAINT MONO (1021 1775);
FORCEPROP 1 LAST OFFPAGE TRUE
J 0
(1600 1650);
DISPLAY 0.872340 (1600 1650);
PAINT AQUA (1600 1650);
DISPLAY INVISIBLE (1600 1650);
FORCEPROP 1 LAST COMMENT_BODY TRUE
J 0
(1375 1700);
DISPLAY 1.170213 (1375 1700);
PAINT GREEN (1375 1700);
DISPLAY INVISIBLE (1375 1700);
FORCEPROP 2 LAST CDS_LIB standard
J 0
(1275 1775);
DISPLAY INVISIBLE (1275 1775);
FORCEPROP 2 LAST PATH I72
J 0
(1025 1825);
DISPLAY 1.021277 (1025 1825);
DISPLAY INVISIBLE (1025 1825);
FORCEADD OFFPAGE..2
R 2
(1275 1825);
FORCEPROP 2 LAST $XR0 29 
J 0
(1021 1825);
DISPLAY 0.638298 (1021 1825);
PAINT MONO (1021 1825);
FORCEPROP 1 LAST OFFPAGE TRUE
J 2
(950 1700);
DISPLAY 0.872340 (950 1700);
PAINT AQUA (950 1700);
DISPLAY INVISIBLE (950 1700);
FORCEPROP 1 LAST COMMENT_BODY TRUE
J 2
(1320 1730);
DISPLAY 0.872340 (1320 1730);
PAINT GREEN (1320 1730);
DISPLAY INVISIBLE (1320 1730);
FORCEPROP 2 LAST CDS_LIB standard
J 0
(1275 1825);
DISPLAY INVISIBLE (1275 1825);
FORCEPROP 2 LAST PATH I73
J 0
(1025 1875);
DISPLAY 1.021277 (1025 1875);
DISPLAY INVISIBLE (1025 1875);
FORCEADD OFFPAGE..5
(1275 1625);
FORCEPROP 2 LAST $XR0 31 
J 0
(1021 1625);
DISPLAY 0.638298 (1021 1625);
PAINT MONO (1021 1625);
FORCEPROP 2 LAST CDS_LIB standard
J 0
(1275 1625);
DISPLAY INVISIBLE (1275 1625);
FORCEPROP 1 LAST COMMENT_BODY TRUE
J 0
(1375 1550);
DISPLAY 1.170213 (1375 1550);
PAINT GREEN (1375 1550);
DISPLAY INVISIBLE (1375 1550);
FORCEPROP 1 LAST OFFPAGE TRUE
J 0
(1600 1500);
DISPLAY 0.872340 (1600 1500);
PAINT AQUA (1600 1500);
DISPLAY INVISIBLE (1600 1500);
FORCEPROP 2 LAST PATH I74
J 0
(1025 1675);
DISPLAY 1.021277 (1025 1675);
DISPLAY INVISIBLE (1025 1675);
FORCEADD OFFPAGE..2
R 2
(1275 1675);
FORCEPROP 2 LAST $XR0 31 
J 0
(1021 1675);
DISPLAY 0.638298 (1021 1675);
PAINT MONO (1021 1675);
FORCEPROP 2 LAST CDS_LIB standard
J 0
(1275 1675);
DISPLAY INVISIBLE (1275 1675);
FORCEPROP 1 LAST COMMENT_BODY TRUE
J 2
(1320 1580);
DISPLAY 0.872340 (1320 1580);
PAINT GREEN (1320 1580);
DISPLAY INVISIBLE (1320 1580);
FORCEPROP 1 LAST OFFPAGE TRUE
J 2
(950 1550);
DISPLAY 0.872340 (950 1550);
PAINT AQUA (950 1550);
DISPLAY INVISIBLE (950 1550);
FORCEPROP 2 LAST PATH I75
J 0
(1025 1725);
DISPLAY 1.021277 (1025 1725);
DISPLAY INVISIBLE (1025 1725);
FORCEADD CONN112_10137002101LF..1
(-1050 425);
FORCEPROP 1 LAST PART_NUMBER DFHSB2FR012
J 0
(-1800 2175);
DISPLAY 0.723404 (-1800 2175);
PAINT GREEN (-1800 2175);
DISPLAY INVISIBLE (-1800 2175);
FORCEPROP 2 LAST PART_TYPE THLF
J 0
(-1800 2300);
DISPLAY 1.021277 (-1800 2300);
FORCEPROP 1 LAST MATERIAL IO
J 0
(-1795 2107);
DISPLAY 0.723404 (-1795 2107);
PAINT GREEN (-1795 2107);
FORCEPROP 1 LAST LOCATION J108
J 0
(-1800 2225);
DISPLAY 0.723404 (-1800 2225);
PAINT GREEN (-1800 2225);
FORCEPROP 0 LASTPIN (-1975 -475) $PN A5
J 2
(-1985 -465);
DISPLAY 0.680851 (-1985 -465);
PAINT MONO (-1985 -465);
FORCEPROP 0 LASTPIN (-1975 325) $PN A6
J 2
(-1985 335);
DISPLAY 0.680851 (-1985 335);
PAINT MONO (-1985 335);
FORCEPROP 0 LASTPIN (-1975 1125) $PN A7
J 2
(-1985 1135);
DISPLAY 0.680851 (-1985 1135);
PAINT MONO (-1985 1135);
FORCEPROP 0 LASTPIN (-1975 1925) $PN A8
J 2
(-1985 1935);
DISPLAY 0.680851 (-1985 1935);
PAINT MONO (-1985 1935);
FORCEPROP 0 LASTPIN (-1975 -525) $PN B5
J 2
(-1985 -515);
DISPLAY 0.680851 (-1985 -515);
PAINT MONO (-1985 -515);
FORCEPROP 0 LASTPIN (-1975 275) $PN B6
J 2
(-1985 285);
DISPLAY 0.680851 (-1985 285);
PAINT MONO (-1985 285);
FORCEPROP 0 LASTPIN (-1975 1075) $PN B7
J 2
(-1985 1085);
DISPLAY 0.680851 (-1985 1085);
PAINT MONO (-1985 1085);
FORCEPROP 0 LASTPIN (-1975 1875) $PN B8
J 2
(-1985 1885);
DISPLAY 0.680851 (-1985 1885);
PAINT MONO (-1985 1885);
FORCEPROP 0 LASTPIN (-1975 -575) $PN C5
J 2
(-1985 -565);
DISPLAY 0.680851 (-1985 -565);
PAINT MONO (-1985 -565);
FORCEPROP 0 LASTPIN (-1975 225) $PN C6
J 2
(-1985 235);
DISPLAY 0.680851 (-1985 235);
PAINT MONO (-1985 235);
FORCEPROP 0 LASTPIN (-1975 1025) $PN C7
J 2
(-1985 1035);
DISPLAY 0.680851 (-1985 1035);
PAINT MONO (-1985 1035);
FORCEPROP 0 LASTPIN (-1975 1825) $PN C8
J 2
(-1985 1835);
DISPLAY 0.680851 (-1985 1835);
PAINT MONO (-1985 1835);
FORCEPROP 0 LASTPIN (-1975 -625) $PN D5
J 2
(-1985 -615);
DISPLAY 0.680851 (-1985 -615);
PAINT MONO (-1985 -615);
FORCEPROP 0 LASTPIN (-1975 175) $PN D6
J 2
(-1985 185);
DISPLAY 0.680851 (-1985 185);
PAINT MONO (-1985 185);
FORCEPROP 0 LASTPIN (-1975 975) $PN D7
J 2
(-1985 985);
DISPLAY 0.680851 (-1985 985);
PAINT MONO (-1985 985);
FORCEPROP 0 LASTPIN (-1975 1775) $PN D8
J 2
(-1985 1785);
DISPLAY 0.680851 (-1985 1785);
PAINT MONO (-1985 1785);
FORCEPROP 0 LASTPIN (-1975 -675) $PN E5
J 2
(-1985 -665);
DISPLAY 0.680851 (-1985 -665);
PAINT MONO (-1985 -665);
FORCEPROP 0 LASTPIN (-1975 125) $PN E6
J 2
(-1985 135);
DISPLAY 0.680851 (-1985 135);
PAINT MONO (-1985 135);
FORCEPROP 0 LASTPIN (-1975 925) $PN E7
J 2
(-1985 935);
DISPLAY 0.680851 (-1985 935);
PAINT MONO (-1985 935);
FORCEPROP 0 LASTPIN (-1975 1725) $PN E8
J 2
(-1985 1735);
DISPLAY 0.680851 (-1985 1735);
PAINT MONO (-1985 1735);
FORCEPROP 0 LASTPIN (-1975 -725) $PN F5
J 2
(-1985 -715);
DISPLAY 0.680851 (-1985 -715);
PAINT MONO (-1985 -715);
FORCEPROP 0 LASTPIN (-1975 75) $PN F6
J 2
(-1985 85);
DISPLAY 0.680851 (-1985 85);
PAINT MONO (-1985 85);
FORCEPROP 0 LASTPIN (-1975 875) $PN F7
J 2
(-1985 885);
DISPLAY 0.680851 (-1985 885);
PAINT MONO (-1985 885);
FORCEPROP 0 LASTPIN (-1975 1675) $PN F8
J 2
(-1985 1685);
DISPLAY 0.680851 (-1985 1685);
PAINT MONO (-1985 1685);
FORCEPROP 0 LASTPIN (-1975 -775) $PN G5
J 2
(-1985 -765);
DISPLAY 0.680851 (-1985 -765);
PAINT MONO (-1985 -765);
FORCEPROP 0 LASTPIN (-1975 25) $PN G6
J 2
(-1985 35);
DISPLAY 0.680851 (-1985 35);
PAINT MONO (-1985 35);
FORCEPROP 0 LASTPIN (-1975 825) $PN G7
J 2
(-1985 835);
DISPLAY 0.680851 (-1985 835);
PAINT MONO (-1985 835);
FORCEPROP 0 LASTPIN (-1975 1625) $PN G8
J 2
(-1985 1635);
DISPLAY 0.680851 (-1985 1635);
PAINT MONO (-1985 1635);
FORCEPROP 0 LASTPIN (-1975 -825) $PN H5
J 2
(-1985 -815);
DISPLAY 0.680851 (-1985 -815);
PAINT MONO (-1985 -815);
FORCEPROP 0 LASTPIN (-1975 -25) $PN H6
J 2
(-1985 -15);
DISPLAY 0.680851 (-1985 -15);
PAINT MONO (-1985 -15);
FORCEPROP 0 LASTPIN (-1975 775) $PN H7
J 2
(-1985 785);
DISPLAY 0.680851 (-1985 785);
PAINT MONO (-1985 785);
FORCEPROP 0 LASTPIN (-1975 1575) $PN H8
J 2
(-1985 1585);
DISPLAY 0.680851 (-1985 1585);
PAINT MONO (-1985 1585);
FORCEPROP 0 LASTPIN (-1975 -875) $PN I5
J 2
(-1985 -865);
DISPLAY 0.680851 (-1985 -865);
PAINT MONO (-1985 -865);
FORCEPROP 0 LASTPIN (-1975 -75) $PN I6
J 2
(-1985 -65);
DISPLAY 0.680851 (-1985 -65);
PAINT MONO (-1985 -65);
FORCEPROP 0 LASTPIN (-1975 725) $PN I7
J 2
(-1985 735);
DISPLAY 0.680851 (-1985 735);
PAINT MONO (-1985 735);
FORCEPROP 0 LASTPIN (-1975 1525) $PN I8
J 2
(-1985 1535);
DISPLAY 0.680851 (-1985 1535);
PAINT MONO (-1985 1535);
FORCEPROP 0 LASTPIN (-1975 -925) $PN J5
J 2
(-1985 -915);
DISPLAY 0.680851 (-1985 -915);
PAINT MONO (-1985 -915);
FORCEPROP 0 LASTPIN (-1975 -125) $PN J6
J 2
(-1985 -115);
DISPLAY 0.680851 (-1985 -115);
PAINT MONO (-1985 -115);
FORCEPROP 0 LASTPIN (-1975 675) $PN J7
J 2
(-1985 685);
DISPLAY 0.680851 (-1985 685);
PAINT MONO (-1985 685);
FORCEPROP 0 LASTPIN (-1975 1475) $PN J8
J 2
(-1985 1485);
DISPLAY 0.680851 (-1985 1485);
PAINT MONO (-1985 1485);
FORCEPROP 0 LASTPIN (-1975 -975) $PN K5
J 2
(-1985 -965);
DISPLAY 0.680851 (-1985 -965);
PAINT MONO (-1985 -965);
FORCEPROP 0 LASTPIN (-1975 -175) $PN K6
J 2
(-1985 -165);
DISPLAY 0.680851 (-1985 -165);
PAINT MONO (-1985 -165);
FORCEPROP 0 LASTPIN (-1975 625) $PN K7
J 2
(-1985 635);
DISPLAY 0.680851 (-1985 635);
PAINT MONO (-1985 635);
FORCEPROP 0 LASTPIN (-1975 1425) $PN K8
J 2
(-1985 1435);
DISPLAY 0.680851 (-1985 1435);
PAINT MONO (-1985 1435);
FORCEPROP 0 LASTPIN (-1975 -1025) $PN L5
J 2
(-1985 -1015);
DISPLAY 0.680851 (-1985 -1015);
PAINT MONO (-1985 -1015);
FORCEPROP 0 LASTPIN (-1975 -225) $PN L6
J 2
(-1985 -215);
DISPLAY 0.680851 (-1985 -215);
PAINT MONO (-1985 -215);
FORCEPROP 0 LASTPIN (-1975 575) $PN L7
J 2
(-1985 585);
DISPLAY 0.680851 (-1985 585);
PAINT MONO (-1985 585);
FORCEPROP 0 LASTPIN (-1975 1375) $PN L8
J 2
(-1985 1385);
DISPLAY 0.680851 (-1985 1385);
PAINT MONO (-1985 1385);
FORCEPROP 0 LASTPIN (-1975 -1075) $PN M5
J 2
(-1985 -1065);
DISPLAY 0.680851 (-1985 -1065);
PAINT MONO (-1985 -1065);
FORCEPROP 0 LASTPIN (-1975 -275) $PN M6
J 2
(-1985 -265);
DISPLAY 0.680851 (-1985 -265);
PAINT MONO (-1985 -265);
FORCEPROP 0 LASTPIN (-1975 525) $PN M7
J 2
(-1985 535);
DISPLAY 0.680851 (-1985 535);
PAINT MONO (-1985 535);
FORCEPROP 0 LASTPIN (-1975 1325) $PN M8
J 2
(-1985 1335);
DISPLAY 0.680851 (-1985 1335);
PAINT MONO (-1985 1335);
FORCEPROP 0 LASTPIN (-1975 -1125) $PN N5
J 2
(-1985 -1115);
DISPLAY 0.680851 (-1985 -1115);
PAINT MONO (-1985 -1115);
FORCEPROP 0 LASTPIN (-1975 -325) $PN N6
J 2
(-1985 -315);
DISPLAY 0.680851 (-1985 -315);
PAINT MONO (-1985 -315);
FORCEPROP 0 LASTPIN (-1975 475) $PN N7
J 2
(-1985 485);
DISPLAY 0.680851 (-1985 485);
PAINT MONO (-1985 485);
FORCEPROP 0 LASTPIN (-1975 1275) $PN N8
J 2
(-1985 1285);
DISPLAY 0.680851 (-1985 1285);
PAINT MONO (-1985 1285);
FORCEPROP 0 LAST VALUE CONN112_10137002-101LF
J 0
(-1775 2425);
DISPLAY 1.021277 (-1775 2425);
DISPLAY INVISIBLE (-1775 2425);
FORCEPROP 1 LAST CDS_LMAN_SYM_OUTLINE -775,1650,775,-1650
J 0
(-1050 425);
DISPLAY 0.468085 (-1050 425);
PAINT GREEN (-1050 425);
DISPLAY INVISIBLE (-1050 425);
FORCEPROP 1 LAST NEEDS_NO_SIZE TRUE
J 0
(-1050 425);
DISPLAY 0.723404 (-1050 425);
PAINT GREEN (-1050 425);
DISPLAY INVISIBLE (-1050 425);
FORCEPROP 2 LAST CDS_LIB pure_quanta
J 0
(-1050 425);
DISPLAY INVISIBLE (-1050 425);
FORCEPROP 1 LAST PATH I76
J 0
(-1050 425);
DISPLAY 0.723404 (-1050 425);
PAINT GREEN (-1050 425);
DISPLAY INVISIBLE (-1050 425);
FORCEPROP 0 LAST $SEC 1
J 0
(-1800 2350);
DISPLAY 0.680851 (-1800 2350);
PAINT MONO (-1800 2350);
DISPLAY INVISIBLE (-1800 2350);
FORCEPROP 0 LAST CDS_SEC 1
J 0
(-1800 2350);
DISPLAY 1.021277 (-1800 2350);
DISPLAY INVISIBLE (-1800 2350);
FORCEADD OFFPAGE..2
R 2
(-3250 1125);
FORCEPROP 2 LAST $XR0 147 
J 0
(-3535 1125);
DISPLAY 0.638298 (-3535 1125);
PAINT MONO (-3535 1125);
FORCEPROP 2 LAST CDS_LIB standard
J 0
(-3250 1125);
DISPLAY INVISIBLE (-3250 1125);
FORCEPROP 1 LAST COMMENT_BODY TRUE
J 2
(-3205 1030);
DISPLAY 0.872340 (-3205 1030);
PAINT GREEN (-3205 1030);
DISPLAY INVISIBLE (-3205 1030);
FORCEPROP 1 LAST OFFPAGE TRUE
J 2
(-3575 1000);
DISPLAY 0.872340 (-3575 1000);
PAINT AQUA (-3575 1000);
DISPLAY INVISIBLE (-3575 1000);
FORCEPROP 2 LAST PATH I77
J 0
(-3500 1175);
DISPLAY 1.021277 (-3500 1175);
DISPLAY INVISIBLE (-3500 1175);
FORCEADD OFFPAGE..2
R 2
(1300 -525);
FORCEPROP 2 LAST $XR0 146 
J 0
(1045 -525);
DISPLAY 0.638298 (1045 -525);
PAINT MONO (1045 -525);
FORCEPROP 1 LAST OFFPAGE TRUE
J 2
(975 -650);
DISPLAY 0.872340 (975 -650);
PAINT AQUA (975 -650);
DISPLAY INVISIBLE (975 -650);
FORCEPROP 1 LAST COMMENT_BODY TRUE
J 2
(1345 -620);
DISPLAY 0.872340 (1345 -620);
PAINT GREEN (1345 -620);
DISPLAY INVISIBLE (1345 -620);
FORCEPROP 2 LAST CDS_LIB standard
J 0
(1300 -525);
DISPLAY INVISIBLE (1300 -525);
FORCEPROP 2 LAST PATH I78
J 0
(1050 -475);
DISPLAY 1.021277 (1050 -475);
DISPLAY INVISIBLE (1050 -475);
FORCEADD OFFPAGE..2
R 2
(1300 1075);
FORCEPROP 2 LAST $XR0 146 
J 0
(1045 1075);
DISPLAY 0.638298 (1045 1075);
PAINT MONO (1045 1075);
FORCEPROP 1 LAST OFFPAGE TRUE
J 2
(975 950);
DISPLAY 0.872340 (975 950);
PAINT AQUA (975 950);
DISPLAY INVISIBLE (975 950);
FORCEPROP 1 LAST COMMENT_BODY TRUE
J 2
(1345 980);
DISPLAY 0.872340 (1345 980);
PAINT GREEN (1345 980);
DISPLAY INVISIBLE (1345 980);
FORCEPROP 2 LAST CDS_LIB standard
J 0
(1300 1075);
DISPLAY INVISIBLE (1300 1075);
FORCEPROP 2 LAST PATH I79
J 0
(1050 1125);
DISPLAY 1.021277 (1050 1125);
DISPLAY INVISIBLE (1050 1125);
FORCEADD OFFPAGE..2
R 2
(-3250 -575);
FORCEPROP 2 LAST $XR0 29 
J 0
(-3504 -575);
DISPLAY 0.638298 (-3504 -575);
PAINT MONO (-3504 -575);
FORCEPROP 2 LAST PATH I8
J 0
(-3500 -525);
DISPLAY 1.021277 (-3500 -525);
DISPLAY INVISIBLE (-3500 -525);
FORCEPROP 2 LAST CDS_LIB standard
J 0
(-3250 -575);
DISPLAY INVISIBLE (-3250 -575);
FORCEPROP 1 LAST COMMENT_BODY TRUE
J 2
(-3205 -670);
DISPLAY 0.872340 (-3205 -670);
PAINT GREEN (-3205 -670);
DISPLAY INVISIBLE (-3205 -670);
FORCEPROP 1 LAST OFFPAGE TRUE
J 2
(-3575 -700);
DISPLAY 0.872340 (-3575 -700);
PAINT AQUA (-3575 -700);
DISPLAY INVISIBLE (-3575 -700);
FORCEADD OFFPAGE..2
R 2
(-3250 -475);
FORCEPROP 2 LAST $XR0 146 
J 0
(-3535 -475);
DISPLAY 0.638298 (-3535 -475);
PAINT MONO (-3535 -475);
FORCEPROP 1 LAST OFFPAGE TRUE
J 2
(-3575 -600);
DISPLAY 0.872340 (-3575 -600);
PAINT AQUA (-3575 -600);
DISPLAY INVISIBLE (-3575 -600);
FORCEPROP 1 LAST COMMENT_BODY TRUE
J 2
(-3205 -570);
DISPLAY 0.872340 (-3205 -570);
PAINT GREEN (-3205 -570);
DISPLAY INVISIBLE (-3205 -570);
FORCEPROP 2 LAST CDS_LIB standard
J 0
(-3250 -475);
DISPLAY INVISIBLE (-3250 -475);
FORCEPROP 2 LAST PATH I80
J 0
(-3500 -425);
DISPLAY 1.021277 (-3500 -425);
DISPLAY INVISIBLE (-3500 -425);
FORCEADD OFFPAGE..5
(-3250 1275);
FORCEPROP 2 LAST $XR0 144 
J 0
(-3535 1275);
DISPLAY 0.638298 (-3535 1275);
PAINT MONO (-3535 1275);
FORCEPROP 1 LAST OFFPAGE TRUE
J 0
(-2925 1150);
DISPLAY 0.872340 (-2925 1150);
PAINT AQUA (-2925 1150);
DISPLAY INVISIBLE (-2925 1150);
FORCEPROP 1 LAST COMMENT_BODY TRUE
J 0
(-3150 1200);
DISPLAY 1.170213 (-3150 1200);
PAINT GREEN (-3150 1200);
DISPLAY INVISIBLE (-3150 1200);
FORCEPROP 2 LAST PATH I81
J 0
(-3200 1350);
DISPLAY 1.021277 (-3200 1350);
DISPLAY INVISIBLE (-3200 1350);
FORCEPROP 2 LAST CDS_LIB standard
J 0
(-3250 1275);
DISPLAY INVISIBLE (-3250 1275);
FORCEADD QUANTA_TITLE_BLOCK_C..1
(4725 -3300);
FORCEPROP 0 LAST CDS_CON_LAST_MODIFIED Fri Aug 25 14:02:00 2023
J 0
(2840 -3285);
PAINT MONO (2840 -3285);
DISPLAY INVISIBLE (2840 -3285);
FORCEPROP 2 LAST CUSTOM_TXT_CDS <XR_PAGE_TITLE>
J 0
(-3165 1950);
DISPLAY 0.638298 (-3165 1950);
PAINT PINK (-3165 1950);
DISPLAY INVISIBLE (-3165 1950);
FORCEPROP 2 LAST CUSTOM_TXT_CDS <Q_NUMBER>
J 0
(3322 -3197);
DISPLAY 1.212766 (3322 -3197);
FORCEPROP 2 LAST CUSTOM_TXT_CDS <CON_LAST_MODIFIED>
J 0
(2800 -3300);
DISPLAY 0.978723 (2800 -3300);
FORCEPROP 2 LAST CUSTOM_TXT_CDS <Q_REV>
J 0
(4541 -3197);
DISPLAY 1.212766 (4541 -3197);
FORCEPROP 2 LAST CUSTOM_TXT_CDS <NAME_2>
J 0
(1550 -3250);
FORCEPROP 2 LAST CUSTOM_TXT_CDS <NAME_1>
J 0
(1550 -3125);
FORCEPROP 2 LAST CUSTOM_TXT_CDS <Q_PROJ>
J 0
(2343 -3198);
DISPLAY 1.212766 (2343 -3198);
FORCEPROP 1 LAST CUSTOM_TXT_CDS <CON_PAGE_NUM> OF <CON_TOTAL_PAGES>
J 0
(4279 -3282);
DISPLAY 0.978723 (4279 -3282);
FORCEPROP 1 LAST Q_TITLE PCIE - CPU0_EXAMAX_P0/P4_X16
J 0
(-4550 -3250);
DISPLAY 1.957447 (-4550 -3250);
PAINT GREEN (-4550 -3250);
FORCEPROP 1 LAST Q_DEPT 
J 1
(962 -3251);
DISPLAY 1.957447 (962 -3251);
PAINT GREEN (962 -3251);
FORCEPROP 2 LAST CDS_XR_PAGE_TITLE CR-139 : @S9S_MB_2U_LIB.S9S_MB_2U(SCH_1):PAGE139
J 0
(-3165 1950);
DISPLAY 0.638298 (-3165 1950);
PAINT PINK (-3165 1950);
DISPLAY INVISIBLE (-3165 1950);
FORCEPROP 2 LAST CDS_LIB pure_quanta
J 0
(4725 -3300);
PAINT MONO (4725 -3300);
DISPLAY INVISIBLE (4725 -3300);
FORCEPROP 1 LAST CDS_LMAN_SYM_OUTLINE -9475,6775,100,-125
J 0
(4725 -3300);
DISPLAY 0.468085 (4725 -3300);
PAINT GREEN (4725 -3300);
DISPLAY INVISIBLE (4725 -3300);
FORCEPROP 2 LAST PAGE_BORDER TRUE
J 0
(-3165 1950);
DISPLAY 0.638298 (-3165 1950);
PAINT PINK (-3165 1950);
DISPLAY INVISIBLE (-3165 1950);
FORCEPROP 1 LAST COMMENT_BODY TRUE
J 0
(4737 -3313);
DISPLAY 0.978723 (4737 -3313);
PAINT GREEN (4737 -3313);
DISPLAY INVISIBLE (4737 -3313);
WIRE 16 -1 (2350 -1175)(2350 -1525);
WIRE 16 -1 (2350 -1025)(2350 -1175);
WIRE 16 -1 (2575 -1175)(2350 -1175);
WIRE 16 -1 (-2150 -1125)(-2150 -1425);
WIRE 16 -1 (-2150 -975)(-2150 -1125);
WIRE 16 -1 (-1975 -1125)(-2150 -1125);
WIRE 16 -1 (-1975 1275)(-3200 1275);
FORCEPROP 2 LAST SIG_NAME PRSNT_CABLE_GPU_A3_N
J 0
(-3085 1285);
DISPLAY 0.638298 (-3085 1285);
WIRE 16 -1 (-1975 1125)(-3200 1125);
FORCEPROP 2 LAST SIG_NAME GPU_FPGA_OVERT_N
J 0
(-3085 1135);
DISPLAY 0.638298 (-3085 1135);
WIRE 16 -1 (-1975 1025)(-3200 1025);
FORCEPROP 2 LAST SIG_NAME P5E_CPU0_PE0_RX_DN<9>
J 0
(-3085 1035);
DISPLAY 0.638298 (-3085 1035);
WIRE 16 -1 (-1975 975)(-3200 975);
FORCEPROP 2 LAST SIG_NAME P5E_CPU0_PE0_RX_DP<9>
J 0
(-3085 985);
DISPLAY 0.638298 (-3085 985);
WIRE 16 -1 (-1975 825)(-3200 825);
FORCEPROP 2 LAST SIG_NAME P5E_CPU0_PE4_RX_DP<6>
J 0
(-3085 835);
DISPLAY 0.638298 (-3085 835);
WIRE 16 -1 (-1975 1375)(-3200 1375);
FORCEPROP 2 LAST SIG_NAME P5E_CPU0_PE4_TX_C_DP<7>
J 0
(-3085 1385);
DISPLAY 0.638298 (-3085 1385);
WIRE 16 -1 (-1975 525)(-3200 525);
FORCEPROP 2 LAST SIG_NAME P5E_CPU0_PE4_TX_C_DP<6>
J 0
(-3085 535);
DISPLAY 0.638298 (-3085 535);
WIRE 16 -1 (-1975 275)(-3200 275);
FORCEPROP 2 LAST SIG_NAME P5E_CPU0_PE0_RX_DN<10>
J 0
(-3085 285);
DISPLAY 0.638298 (-3085 285);
WIRE 16 -1 (-1975 225)(-3200 225);
FORCEPROP 2 LAST SIG_NAME P5E_CPU0_PE0_RX_DP<10>
J 0
(-3085 235);
DISPLAY 0.638298 (-3085 235);
WIRE 16 -1 (-1975 125)(-3200 125);
FORCEPROP 2 LAST SIG_NAME P5E_CPU0_PE4_RX_DP<5>
J 0
(-3085 135);
DISPLAY 0.638298 (-3085 135);
WIRE 16 -1 (-1975 1925)(-2150 1925);
WIRE 16 -1 (-2150 1925)(-2150 1775);
WIRE 16 -1 (-1975 1775)(-2150 1775);
WIRE 16 -1 (-2150 1775)(-2150 1625);
WIRE 16 -1 (-1975 1625)(-2150 1625);
WIRE 16 -1 (-2150 1625)(-2150 1475);
WIRE 16 -1 (-1975 1475)(-2150 1475);
WIRE 16 -1 (-2150 1475)(-2150 1325);
WIRE 16 -1 (-1975 1325)(-2150 1325);
WIRE 16 -1 (-2150 1325)(-2150 1075);
WIRE 16 -1 (-1975 1075)(-2150 1075);
WIRE 16 -1 (-2150 1075)(-2150 925);
WIRE 16 -1 (-1975 925)(-2150 925);
WIRE 16 -1 (-2150 925)(-2150 775);
WIRE 16 -1 (-1975 775)(-2150 775);
WIRE 16 -1 (-2150 775)(-2150 625);
WIRE 16 -1 (-1975 625)(-2150 625);
WIRE 16 -1 (-2150 625)(-2150 475);
WIRE 16 -1 (-1975 475)(-2150 475);
WIRE 16 -1 (-2150 475)(-2150 325);
WIRE 16 -1 (-1975 325)(-2150 325);
WIRE 16 -1 (-2150 325)(-2150 175);
WIRE 16 -1 (-1975 175)(-2150 175);
WIRE 16 -1 (-2150 175)(-2150 25);
WIRE 16 -1 (-1975 25)(-2150 25);
WIRE 16 -1 (-1975 -125)(-2150 -125);
WIRE 16 -1 (-2150 25)(-2150 -125);
WIRE 16 -1 (-2150 -125)(-2150 -275);
WIRE 16 -1 (-1975 -275)(-2150 -275);
WIRE 16 -1 (-2150 -275)(-2150 -525);
WIRE 16 -1 (-1975 -525)(-2150 -525);
WIRE 16 -1 (-2150 -675)(-2150 -525);
WIRE 16 -1 (-1975 -675)(-2150 -675);
WIRE 16 -1 (-2150 -825)(-2150 -675);
WIRE 16 -1 (-1975 -825)(-2150 -825);
WIRE 16 -1 (-2150 -825)(-2150 -975);
WIRE 16 -1 (-1975 -975)(-2150 -975);
WIRE 16 -1 (-1975 75)(-3200 75);
FORCEPROP 2 LAST SIG_NAME P5E_CPU0_PE4_RX_DN<5>
J 0
(-3085 85);
DISPLAY 0.638298 (-3085 85);
WIRE 16 -1 (-1975 -25)(-3200 -25);
FORCEPROP 2 LAST SIG_NAME P5E_CPU0_PE0_TX_C_DN<10>
J 0
(-3085 -15);
DISPLAY 0.638298 (-3085 -15);
WIRE 16 -1 (-1975 -75)(-3200 -75);
FORCEPROP 2 LAST SIG_NAME P5E_CPU0_PE0_TX_C_DP<10>
J 0
(-3085 -65);
DISPLAY 0.638298 (-3085 -65);
WIRE 16 -1 (-1975 -175)(-3200 -175);
FORCEPROP 2 LAST SIG_NAME P5E_CPU0_PE4_TX_C_DN<5>
J 0
(-3085 -165);
DISPLAY 0.638298 (-3085 -165);
WIRE 16 -1 (-1975 -225)(-3200 -225);
FORCEPROP 2 LAST SIG_NAME P5E_CPU0_PE4_TX_C_DP<5>
J 0
(-3085 -215);
DISPLAY 0.638298 (-3085 -215);
WIRE 16 -1 (-1975 -325)(-3200 -325);
FORCEPROP 2 LAST SIG_NAME NC_J108_N6
J 0
(-3085 -315);
DISPLAY 0.638298 (-3085 -315);
WIRE 16 -1 (-1975 675)(-3200 675);
FORCEPROP 2 LAST SIG_NAME P5E_CPU0_PE0_TX_C_DP<9>
J 0
(-3085 685);
DISPLAY 0.638298 (-3085 685);
WIRE 16 -1 (-1975 875)(-3200 875);
FORCEPROP 2 LAST SIG_NAME P5E_CPU0_PE4_RX_DN<6>
J 0
(-3085 885);
DISPLAY 0.638298 (-3085 885);
WIRE 16 -1 (2575 475)(1325 475);
FORCEPROP 2 LAST SIG_NAME P5E_CPU0_PE4_TX_C_DP<2>
J 0
(1440 485);
DISPLAY 0.638298 (1440 485);
WIRE 16 -1 (2575 1075)(1350 1075);
FORCEPROP 2 LAST SIG_NAME PRSNT_CABLE_GPU_A2_N
J 0
(1440 1085);
DISPLAY 0.638298 (1440 1085);
WIRE 16 -1 (2575 1225)(1350 1225);
FORCEPROP 2 LAST SIG_NAME NC_J108_N4
J 0
(1465 1235);
DISPLAY 0.638298 (1465 1235);
WIRE 16 -1 (2575 1325)(1325 1325);
FORCEPROP 2 LAST SIG_NAME P5E_CPU0_PE4_TX_C_DP<3>
J 0
(1440 1335);
DISPLAY 0.638298 (1440 1335);
WIRE 16 -1 (2575 975)(1325 975);
FORCEPROP 2 LAST SIG_NAME P5E_CPU0_PE0_RX_DN<13>
J 0
(1440 985);
DISPLAY 0.638298 (1440 985);
WIRE 16 -1 (2575 925)(1325 925);
FORCEPROP 2 LAST SIG_NAME P5E_CPU0_PE0_RX_DP<13>
J 0
(1440 935);
DISPLAY 0.638298 (1440 935);
WIRE 16 -1 (2575 825)(1325 825);
FORCEPROP 2 LAST SIG_NAME P5E_CPU0_PE4_RX_DN<2>
J 0
(1440 835);
DISPLAY 0.638298 (1440 835);
WIRE 16 -1 (2575 775)(1325 775);
FORCEPROP 2 LAST SIG_NAME P5E_CPU0_PE4_RX_DP<2>
J 0
(1440 785);
DISPLAY 0.638298 (1440 785);
WIRE 16 -1 (2575 625)(1325 625);
FORCEPROP 2 LAST SIG_NAME P5E_CPU0_PE0_TX_C_DP<13>
J 0
(1440 635);
DISPLAY 0.638298 (1440 635);
WIRE 16 -1 (2575 525)(1325 525);
FORCEPROP 2 LAST SIG_NAME P5E_CPU0_PE4_TX_C_DN<2>
J 0
(1440 535);
DISPLAY 0.638298 (1440 535);
WIRE 16 -1 (2575 225)(1325 225);
FORCEPROP 2 LAST SIG_NAME P5E_CPU0_PE0_RX_DN<14>
J 0
(1440 235);
DISPLAY 0.638298 (1440 235);
WIRE 16 -1 (2575 75)(1325 75);
FORCEPROP 2 LAST SIG_NAME P5E_CPU0_PE4_RX_DP<1>
J 0
(1440 85);
DISPLAY 0.638298 (1440 85);
WIRE 16 -1 (2575 -125)(1325 -125);
FORCEPROP 2 LAST SIG_NAME P5E_CPU0_PE0_TX_C_DP<14>
J 0
(1440 -115);
DISPLAY 0.638298 (1440 -115);
WIRE 16 -1 (2575 -225)(1325 -225);
FORCEPROP 2 LAST SIG_NAME P5E_CPU0_PE4_TX_C_DP<1>
J 0
(1440 -215);
DISPLAY 0.638298 (1440 -215);
WIRE 16 -1 (2575 1875)(2350 1875);
WIRE 16 -1 (2350 1875)(2350 1725);
WIRE 16 -1 (2575 1725)(2350 1725);
WIRE 16 -1 (2350 1725)(2350 1575);
WIRE 16 -1 (2575 1575)(2350 1575);
WIRE 16 -1 (2350 1575)(2350 1425);
WIRE 16 -1 (2575 1425)(2350 1425);
WIRE 16 -1 (2350 1425)(2350 1275);
WIRE 16 -1 (2575 1275)(2350 1275);
WIRE 16 -1 (2350 1275)(2350 1025);
WIRE 16 -1 (2575 1025)(2350 1025);
WIRE 16 -1 (2575 875)(2350 875);
WIRE 16 -1 (2350 1025)(2350 875);
WIRE 16 -1 (2350 875)(2350 725);
WIRE 16 -1 (2575 725)(2350 725);
WIRE 16 -1 (2350 725)(2350 575);
WIRE 16 -1 (2575 575)(2350 575);
WIRE 16 -1 (2350 575)(2350 425);
WIRE 16 -1 (2575 425)(2350 425);
WIRE 16 -1 (2350 425)(2350 275);
WIRE 16 -1 (2575 275)(2350 275);
WIRE 16 -1 (2350 275)(2350 125);
WIRE 16 -1 (2575 125)(2350 125);
WIRE 16 -1 (2575 -25)(2350 -25);
WIRE 16 -1 (2350 125)(2350 -25);
WIRE 16 -1 (2350 -25)(2350 -175);
WIRE 16 -1 (2575 -175)(2350 -175);
WIRE 16 -1 (2350 -175)(2350 -325);
WIRE 16 -1 (2575 -325)(2350 -325);
WIRE 16 -1 (2350 -325)(2350 -575);
WIRE 16 -1 (2575 -575)(2350 -575);
WIRE 16 -1 (2350 -575)(2350 -725);
WIRE 16 -1 (2575 -725)(2350 -725);
WIRE 16 -1 (2350 -725)(2350 -875);
WIRE 16 -1 (2575 -875)(2350 -875);
WIRE 16 -1 (2350 -875)(2350 -1025);
WIRE 16 -1 (2575 -1025)(2350 -1025);
WIRE 16 -1 (2575 675)(1325 675);
FORCEPROP 2 LAST SIG_NAME P5E_CPU0_PE0_TX_C_DN<13>
J 0
(1440 685);
DISPLAY 0.638298 (1440 685);
WIRE 16 -1 (2575 -75)(1325 -75);
FORCEPROP 2 LAST SIG_NAME P5E_CPU0_PE0_TX_C_DN<14>
J 0
(1440 -65);
DISPLAY 0.638298 (1440 -65);
WIRE 16 -1 (2575 25)(1325 25);
FORCEPROP 2 LAST SIG_NAME P5E_CPU0_PE4_RX_DN<1>
J 0
(1440 35);
DISPLAY 0.638298 (1440 35);
WIRE 16 -1 (2575 175)(1325 175);
FORCEPROP 2 LAST SIG_NAME P5E_CPU0_PE0_RX_DP<14>
J 0
(1440 185);
DISPLAY 0.638298 (1440 185);
WIRE 16 -1 (2575 -275)(1325 -275);
FORCEPROP 2 LAST SIG_NAME P5E_CPU0_PE4_TX_C_DN<1>
J 0
(1440 -265);
DISPLAY 0.638298 (1440 -265);
WIRE 16 -1 (2575 -375)(1350 -375);
FORCEPROP 2 LAST SIG_NAME NC_J108_N2
J 0
(1465 -365);
DISPLAY 0.638298 (1465 -365);
WIRE 16 -1 (-1975 1425)(-3200 1425);
FORCEPROP 2 LAST SIG_NAME P5E_CPU0_PE4_TX_C_DN<7>
J 0
(-3085 1435);
DISPLAY 0.638298 (-3085 1435);
WIRE 16 -1 (-1975 1525)(-3200 1525);
FORCEPROP 2 LAST SIG_NAME P5E_CPU0_PE0_TX_C_DP<8>
J 0
(-3085 1535);
DISPLAY 0.638298 (-3085 1535);
WIRE 16 -1 (-1975 1575)(-3200 1575);
FORCEPROP 2 LAST SIG_NAME P5E_CPU0_PE0_TX_C_DN<8>
J 0
(-3085 1585);
DISPLAY 0.638298 (-3085 1585);
WIRE 16 -1 (-1975 1825)(-3200 1825);
FORCEPROP 2 LAST SIG_NAME P5E_CPU0_PE0_RX_DP<8>
J 0
(-3085 1835);
DISPLAY 0.638298 (-3085 1835);
WIRE 16 -1 (-1975 1875)(-3200 1875);
FORCEPROP 2 LAST SIG_NAME P5E_CPU0_PE0_RX_DN<8>
J 0
(-3085 1885);
DISPLAY 0.638298 (-3085 1885);
WIRE 16 -1 (-1975 -1075)(-3200 -1075);
FORCEPROP 2 LAST SIG_NAME P5E_CPU0_PE4_TX_C_DP<4>
J 0
(-3085 -1065);
DISPLAY 0.638298 (-3085 -1065);
WIRE 16 -1 (-1975 -1025)(-3200 -1025);
FORCEPROP 2 LAST SIG_NAME P5E_CPU0_PE4_TX_C_DN<4>
J 0
(-3085 -1015);
DISPLAY 0.638298 (-3085 -1015);
WIRE 16 -1 (-1975 575)(-3200 575);
FORCEPROP 2 LAST SIG_NAME P5E_CPU0_PE4_TX_C_DN<6>
J 0
(-3085 585);
DISPLAY 0.638298 (-3085 585);
WIRE 16 -1 (-1975 -925)(-3200 -925);
FORCEPROP 2 LAST SIG_NAME P5E_CPU0_PE0_TX_C_DP<11>
J 0
(-3085 -915);
DISPLAY 0.638298 (-3085 -915);
WIRE 16 -1 (-1975 -875)(-3200 -875);
FORCEPROP 2 LAST SIG_NAME P5E_CPU0_PE0_TX_C_DN<11>
J 0
(-3085 -865);
DISPLAY 0.638298 (-3085 -865);
WIRE 16 -1 (-1975 725)(-3200 725);
FORCEPROP 2 LAST SIG_NAME P5E_CPU0_PE0_TX_C_DN<9>
J 0
(-3085 735);
DISPLAY 0.638298 (-3085 735);
WIRE 16 -1 (-1975 -775)(-3200 -775);
FORCEPROP 2 LAST SIG_NAME P5E_CPU0_PE4_RX_DP<4>
J 0
(-3085 -765);
DISPLAY 0.638298 (-3085 -765);
WIRE 16 -1 (-1975 -725)(-3200 -725);
FORCEPROP 2 LAST SIG_NAME P5E_CPU0_PE4_RX_DN<4>
J 0
(-3085 -715);
DISPLAY 0.638298 (-3085 -715);
WIRE 16 -1 (-1975 1675)(-3200 1675);
FORCEPROP 2 LAST SIG_NAME P5E_CPU0_PE4_RX_DN<7>
J 0
(-3085 1685);
DISPLAY 0.638298 (-3085 1685);
WIRE 16 -1 (-1975 1725)(-3200 1725);
FORCEPROP 2 LAST SIG_NAME P5E_CPU0_PE4_RX_DP<7>
J 0
(-3085 1735);
DISPLAY 0.638298 (-3085 1735);
WIRE 16 -1 (-1975 -625)(-3200 -625);
FORCEPROP 2 LAST SIG_NAME P5E_CPU0_PE0_RX_DN<11>
J 0
(-3085 -615);
DISPLAY 0.638298 (-3085 -615);
WIRE 16 -1 (-1975 -575)(-3200 -575);
FORCEPROP 2 LAST SIG_NAME P5E_CPU0_PE0_RX_DP<11>
J 0
(-3085 -565);
DISPLAY 0.638298 (-3085 -565);
WIRE 16 -1 (-1975 -475)(-3200 -475);
FORCEPROP 2 LAST SIG_NAME GPU_3V3IO_RSVD5_FFU
J 0
(-3085 -465);
DISPLAY 0.638298 (-3085 -465);
WIRE 16 -1 (2575 -525)(1350 -525);
FORCEPROP 2 LAST SIG_NAME GPU_3V3IO_RSVD3_FFU
J 0
(1440 -515);
DISPLAY 0.638298 (1440 -515);
WIRE 16 -1 (2575 1375)(1325 1375);
FORCEPROP 2 LAST SIG_NAME P5E_CPU0_PE4_TX_C_DN<3>
J 0
(1440 1385);
DISPLAY 0.638298 (1440 1385);
WIRE 16 -1 (2575 1475)(1325 1475);
FORCEPROP 2 LAST SIG_NAME P5E_CPU0_PE0_TX_C_DP<12>
J 0
(1440 1485);
DISPLAY 0.638298 (1440 1485);
WIRE 16 -1 (2575 -625)(1325 -625);
FORCEPROP 2 LAST SIG_NAME P5E_CPU0_PE0_RX_DN<15>
J 0
(1440 -615);
DISPLAY 0.638298 (1440 -615);
WIRE 16 -1 (2575 -675)(1325 -675);
FORCEPROP 2 LAST SIG_NAME P5E_CPU0_PE0_RX_DP<15>
J 0
(1440 -665);
DISPLAY 0.638298 (1440 -665);
WIRE 16 -1 (2575 -775)(1325 -775);
FORCEPROP 2 LAST SIG_NAME P5E_CPU0_PE4_RX_DN<0>
J 0
(1440 -765);
DISPLAY 0.638298 (1440 -765);
WIRE 16 -1 (2575 -825)(1325 -825);
FORCEPROP 2 LAST SIG_NAME P5E_CPU0_PE4_RX_DP<0>
J 0
(1440 -815);
DISPLAY 0.638298 (1440 -815);
WIRE 16 -1 (2575 -925)(1325 -925);
FORCEPROP 2 LAST SIG_NAME P5E_CPU0_PE0_TX_C_DN<15>
J 0
(1440 -915);
DISPLAY 0.638298 (1440 -915);
WIRE 16 -1 (2575 -975)(1325 -975);
FORCEPROP 2 LAST SIG_NAME P5E_CPU0_PE0_TX_C_DP<15>
J 0
(1440 -965);
DISPLAY 0.638298 (1440 -965);
WIRE 16 -1 (2575 -1075)(1325 -1075);
FORCEPROP 2 LAST SIG_NAME P5E_CPU0_PE4_TX_C_DN<0>
J 0
(1440 -1065);
DISPLAY 0.638298 (1440 -1065);
WIRE 16 -1 (2575 -1125)(1325 -1125);
FORCEPROP 2 LAST SIG_NAME P5E_CPU0_PE4_TX_C_DP<0>
J 0
(1440 -1115);
DISPLAY 0.638298 (1440 -1115);
WIRE 16 -1 (2575 1525)(1325 1525);
FORCEPROP 2 LAST SIG_NAME P5E_CPU0_PE0_TX_C_DN<12>
J 0
(1440 1535);
DISPLAY 0.638298 (1440 1535);
WIRE 16 -1 (2575 1675)(1325 1675);
FORCEPROP 2 LAST SIG_NAME P5E_CPU0_PE4_RX_DP<3>
J 0
(1440 1685);
DISPLAY 0.638298 (1440 1685);
WIRE 16 -1 (2575 1625)(1325 1625);
FORCEPROP 2 LAST SIG_NAME P5E_CPU0_PE4_RX_DN<3>
J 0
(1440 1635);
DISPLAY 0.638298 (1440 1635);
WIRE 16 -1 (2575 1775)(1325 1775);
FORCEPROP 2 LAST SIG_NAME P5E_CPU0_PE0_RX_DP<12>
J 0
(1440 1785);
DISPLAY 0.638298 (1440 1785);
WIRE 16 -1 (2575 1825)(1325 1825);
FORCEPROP 2 LAST SIG_NAME P5E_CPU0_PE0_RX_DN<12>
J 0
(1440 1835);
DISPLAY 0.638298 (1440 1835);
DOT 1 (-2150 1325);
DOT 1 (-2150 -525);
DOT 1 (-2150 -275);
DOT 1 (-2150 1075);
DOT 1 (-2150 -1125);
DOT 1 (-2150 -825);
DOT 1 (-2150 -975);
DOT 1 (-2150 -125);
DOT 1 (-2150 175);
DOT 1 (-2150 25);
DOT 1 (-2150 475);
DOT 1 (-2150 775);
DOT 1 (-2150 925);
DOT 1 (-2150 1475);
DOT 1 (-2150 1625);
DOT 1 (-2150 1775);
DOT 1 (-2150 -675);
DOT 1 (-2150 325);
DOT 1 (-2150 625);
DOT 1 (2350 1725);
DOT 1 (2350 1575);
DOT 1 (2350 1425);
DOT 1 (2350 1275);
DOT 1 (2350 1025);
DOT 1 (2350 875);
DOT 1 (2350 725);
DOT 1 (2350 575);
DOT 1 (2350 275);
DOT 1 (2350 425);
DOT 1 (2350 125);
DOT 1 (2350 -175);
DOT 1 (2350 -25);
DOT 1 (2350 -325);
DOT 1 (2350 -725);
DOT 1 (2350 -575);
DOT 1 (2350 -875);
DOT 1 (2350 -1025);
DOT 1 (2350 -1175);
FORCENOTE
DP/DN SWAP
(-4050 100) 0;
DISPLAY LEFT (-4050 100);
DISPLAY 1.021277 (-4050 100);
FORCENOTE
DP/DN SWAP
(475 1650) 0;
DISPLAY LEFT (475 1650);
DISPLAY 1.021277 (475 1650);
FORCENOTE
DP/DN SWAP
(450 -250) 0;
DISPLAY LEFT (450 -250);
DISPLAY 1.021277 (450 -250);
FORCENOTE
20210527 MODIFY FOR GT
(-4500 3000) 0;
DISPLAY LEFT (-4500 3000);
DISPLAY 2.510638 (-4500 3000);
PAINT PINK (-4500 3000);
FORCENOTE
CPU0_PE4_TX/RX<0-15> LANE REVERSAL
(-4450 2525) 0;
DISPLAY LEFT (-4450 2525);
DISPLAY 1.276596 (-4450 2525);
PAINT WHITE (-4450 2525);
FORCENOTE
DP/DN SWAP
(425 50) 0;
DISPLAY LEFT (425 50);
DISPLAY 1.021277 (425 50);
FORCENOTE
DP/DN SWAP
(-4050 1675) 0;
DISPLAY LEFT (-4050 1675);
DISPLAY 1.021277 (-4050 1675);
FORCENOTE
DP/DN SWAP
(-4075 -600) 0;
DISPLAY LEFT (-4075 -600);
DISPLAY 1.021277 (-4075 -600);
QUIT
